FILE_TYPE = MACRO_DRAWING;
SET COLOR_WIRE YELLOW;
SET COLOR_PROP ORANGE;
SET COLOR_DOT WHITE;
SET COLOR_ARC YELLOW;
SET COLOR_BODY GREEN;
SET COLOR_NOTE PURPLE;
SET PROP_DISPLAY VALUE;
SET PAGE_NUMBER P211;
FORCEADD UNIVERSAL_GND..1
(-8125 1975);
FORCEPROP 3 LASTPIN (-8125 2025) SIG_NAME DELTA_L_GND_1\g
J 0
(-8115 2035);
DISPLAY 0.659574 (-8115 2035);
PAINT MONO (-8115 2035);
DISPLAY INVISIBLE (-8115 2035);
FORCEPROP 1 LAST HDL_POWER DELTA_L_GND_1
J 1
(-8100 1900);
DISPLAY 0.872340 (-8100 1900);
PAINT GREEN (-8100 1900);
FORCEPROP 2 LAST CDS_LIB pure_quanta_power
J 0
(-8125 1975);
DISPLAY INVISIBLE (-8125 1975);
FORCEPROP 1 LAST PATH I1
J 0
(-8050 1975);
DISPLAY 0.872340 (-8050 1975);
PAINT AQUA (-8050 1975);
DISPLAY INVISIBLE (-8050 1975);
FORCEADD UNIVERSAL_GND..1
(-5175 550);
FORCEPROP 3 LASTPIN (-5175 600) SIG_NAME DELTA_L_GND_1\g
J 0
(-5165 610);
DISPLAY 0.659574 (-5165 610);
PAINT MONO (-5165 610);
DISPLAY INVISIBLE (-5165 610);
FORCEPROP 1 LAST HDL_POWER DELTA_L_GND_1
J 1
(-5150 475);
DISPLAY 0.872340 (-5150 475);
PAINT GREEN (-5150 475);
FORCEPROP 2 LAST CDS_LIB pure_quanta_power
J 0
(-5175 550);
DISPLAY INVISIBLE (-5175 550);
FORCEPROP 1 LAST PATH I16
J 0
(-5100 550);
DISPLAY 0.872340 (-5100 550);
PAINT AQUA (-5100 550);
DISPLAY INVISIBLE (-5100 550);
FORCEADD UNIVERSAL_GND..1
(-5225 1325);
FORCEPROP 3 LASTPIN (-5225 1375) SIG_NAME DELTA_L_GND_1\g
J 0
(-5215 1385);
DISPLAY 0.659574 (-5215 1385);
PAINT MONO (-5215 1385);
DISPLAY INVISIBLE (-5215 1385);
FORCEPROP 1 LAST HDL_POWER DELTA_L_GND_1
J 1
(-5200 1250);
DISPLAY 0.872340 (-5200 1250);
PAINT GREEN (-5200 1250);
FORCEPROP 2 LAST CDS_LIB pure_quanta_power
J 0
(-5225 1325);
DISPLAY INVISIBLE (-5225 1325);
FORCEPROP 1 LAST PATH I19
J 0
(-5150 1325);
DISPLAY 0.872340 (-5150 1325);
PAINT AQUA (-5150 1325);
DISPLAY INVISIBLE (-5150 1325);
FORCEADD UNIVERSAL_GND..1
(-8150 2725);
FORCEPROP 3 LASTPIN (-8150 2775) SIG_NAME DELTA_L_GND_1\g
J 0
(-8140 2785);
DISPLAY 0.659574 (-8140 2785);
PAINT MONO (-8140 2785);
DISPLAY INVISIBLE (-8140 2785);
FORCEPROP 1 LAST HDL_POWER DELTA_L_GND_1
J 1
(-8125 2650);
DISPLAY 0.872340 (-8125 2650);
PAINT GREEN (-8125 2650);
FORCEPROP 2 LAST CDS_LIB pure_quanta_power
J 0
(-8150 2725);
DISPLAY INVISIBLE (-8150 2725);
FORCEPROP 1 LAST PATH I2
J 0
(-8075 2725);
DISPLAY 0.872340 (-8075 2725);
PAINT AQUA (-8075 2725);
DISPLAY INVISIBLE (-8075 2725);
FORCEADD UNIVERSAL_GND..1
(-5250 1975);
FORCEPROP 3 LASTPIN (-5250 2025) SIG_NAME DELTA_L_GND_1\g
J 0
(-5240 2035);
DISPLAY 0.659574 (-5240 2035);
PAINT MONO (-5240 2035);
DISPLAY INVISIBLE (-5240 2035);
FORCEPROP 1 LAST HDL_POWER DELTA_L_GND_1
J 1
(-5225 1900);
DISPLAY 0.872340 (-5225 1900);
PAINT GREEN (-5225 1900);
FORCEPROP 2 LAST CDS_LIB pure_quanta_power
J 0
(-5250 1975);
DISPLAY INVISIBLE (-5250 1975);
FORCEPROP 1 LAST PATH I20
J 0
(-5175 1975);
DISPLAY 0.872340 (-5175 1975);
PAINT AQUA (-5175 1975);
DISPLAY INVISIBLE (-5175 1975);
FORCEADD UNIVERSAL_GND..1
(-5375 2675);
FORCEPROP 3 LASTPIN (-5375 2725) SIG_NAME DELTA_L_GND_1\g
J 0
(-5365 2735);
DISPLAY 0.659574 (-5365 2735);
PAINT MONO (-5365 2735);
DISPLAY INVISIBLE (-5365 2735);
FORCEPROP 1 LAST HDL_POWER DELTA_L_GND_1
J 1
(-5350 2600);
DISPLAY 0.872340 (-5350 2600);
PAINT GREEN (-5350 2600);
FORCEPROP 2 LAST CDS_LIB pure_quanta_power
J 0
(-5375 2675);
DISPLAY INVISIBLE (-5375 2675);
FORCEPROP 1 LAST PATH I22
J 0
(-5300 2675);
DISPLAY 0.872340 (-5300 2675);
PAINT AQUA (-5300 2675);
DISPLAY INVISIBLE (-5300 2675);
FORCEADD UNIVERSAL_GND..1
(-5375 3400);
FORCEPROP 3 LASTPIN (-5375 3450) SIG_NAME DELTA_L_GND_1\g
J 0
(-5365 3460);
DISPLAY 0.659574 (-5365 3460);
PAINT MONO (-5365 3460);
DISPLAY INVISIBLE (-5365 3460);
FORCEPROP 1 LAST HDL_POWER DELTA_L_GND_1
J 1
(-5350 3325);
DISPLAY 0.872340 (-5350 3325);
PAINT GREEN (-5350 3325);
FORCEPROP 2 LAST CDS_LIB pure_quanta_power
J 0
(-5375 3400);
DISPLAY INVISIBLE (-5375 3400);
FORCEPROP 1 LAST PATH I25
J 0
(-5300 3400);
DISPLAY 0.872340 (-5300 3400);
PAINT AQUA (-5300 3400);
DISPLAY INVISIBLE (-5300 3400);
FORCEADD UNIVERSAL_GND..1
(-5350 4150);
FORCEPROP 3 LASTPIN (-5350 4200) SIG_NAME DELTA_L_GND_1\g
J 0
(-5340 4210);
DISPLAY 0.659574 (-5340 4210);
PAINT MONO (-5340 4210);
DISPLAY INVISIBLE (-5340 4210);
FORCEPROP 1 LAST HDL_POWER DELTA_L_GND_1
J 1
(-5325 4075);
DISPLAY 0.872340 (-5325 4075);
PAINT GREEN (-5325 4075);
FORCEPROP 2 LAST CDS_LIB pure_quanta_power
J 0
(-5350 4150);
DISPLAY INVISIBLE (-5350 4150);
FORCEPROP 1 LAST PATH I26
J 0
(-5275 4150);
DISPLAY 0.872340 (-5275 4150);
PAINT AQUA (-5275 4150);
DISPLAY INVISIBLE (-5275 4150);
FORCEADD UNIVERSAL_GND..1
(-8125 3400);
FORCEPROP 3 LASTPIN (-8125 3450) SIG_NAME DELTA_L_GND_1\g
J 0
(-8115 3460);
DISPLAY 0.659574 (-8115 3460);
PAINT MONO (-8115 3460);
DISPLAY INVISIBLE (-8115 3460);
FORCEPROP 1 LAST HDL_POWER DELTA_L_GND_1
J 1
(-8100 3325);
DISPLAY 0.872340 (-8100 3325);
PAINT GREEN (-8100 3325);
FORCEPROP 2 LAST CDS_LIB pure_quanta_power
J 0
(-8125 3400);
DISPLAY INVISIBLE (-8125 3400);
FORCEPROP 1 LAST PATH I3
J 0
(-8050 3400);
DISPLAY 0.872340 (-8050 3400);
PAINT AQUA (-8050 3400);
DISPLAY INVISIBLE (-8050 3400);
FORCEADD UNIVERSAL_GND..1
(-5375 4875);
FORCEPROP 3 LASTPIN (-5375 4925) SIG_NAME DELTA_L_GND_1\g
J 0
(-5365 4935);
DISPLAY 0.659574 (-5365 4935);
PAINT MONO (-5365 4935);
DISPLAY INVISIBLE (-5365 4935);
FORCEPROP 1 LAST HDL_POWER DELTA_L_GND_1
J 1
(-5350 4800);
DISPLAY 0.872340 (-5350 4800);
PAINT GREEN (-5350 4800);
FORCEPROP 2 LAST CDS_LIB pure_quanta_power
J 0
(-5375 4875);
DISPLAY INVISIBLE (-5375 4875);
FORCEPROP 1 LAST PATH I30
J 0
(-5300 4875);
DISPLAY 0.872340 (-5300 4875);
PAINT AQUA (-5300 4875);
DISPLAY INVISIBLE (-5300 4875);
FORCEADD UNIVERSAL_GND..1
(-5375 5650);
FORCEPROP 3 LASTPIN (-5375 5700) SIG_NAME DELTA_L_GND_1\g
J 0
(-5365 5710);
DISPLAY 0.659574 (-5365 5710);
PAINT MONO (-5365 5710);
DISPLAY INVISIBLE (-5365 5710);
FORCEPROP 1 LAST HDL_POWER DELTA_L_GND_1
J 1
(-5350 5575);
DISPLAY 0.872340 (-5350 5575);
PAINT GREEN (-5350 5575);
FORCEPROP 2 LAST CDS_LIB pure_quanta_power
J 0
(-5375 5650);
DISPLAY INVISIBLE (-5375 5650);
FORCEPROP 1 LAST PATH I32
J 0
(-5300 5650);
DISPLAY 0.872340 (-5300 5650);
PAINT AQUA (-5300 5650);
DISPLAY INVISIBLE (-5300 5650);
FORCEADD UNIVERSAL_GND..1
(-4025 650);
FORCEPROP 3 LASTPIN (-4025 700) SIG_NAME DELTA_L_GND_1\g
J 0
(-4015 710);
DISPLAY 0.659574 (-4015 710);
PAINT MONO (-4015 710);
DISPLAY INVISIBLE (-4015 710);
FORCEPROP 1 LAST HDL_POWER DELTA_L_GND_1
J 1
(-4000 575);
DISPLAY 0.872340 (-4000 575);
PAINT GREEN (-4000 575);
FORCEPROP 2 LAST CDS_LIB pure_quanta_power
J 0
(-4025 650);
DISPLAY INVISIBLE (-4025 650);
FORCEPROP 1 LAST PATH I33
J 0
(-3950 650);
DISPLAY 0.872340 (-3950 650);
PAINT AQUA (-3950 650);
DISPLAY INVISIBLE (-3950 650);
FORCEADD UNIVERSAL_GND..1
(-4050 1200);
FORCEPROP 3 LASTPIN (-4050 1250) SIG_NAME DELTA_L_GND_1\g
J 0
(-4040 1260);
DISPLAY 0.659574 (-4040 1260);
PAINT MONO (-4040 1260);
DISPLAY INVISIBLE (-4040 1260);
FORCEPROP 1 LAST HDL_POWER DELTA_L_GND_1
J 1
(-4025 1125);
DISPLAY 0.872340 (-4025 1125);
PAINT GREEN (-4025 1125);
FORCEPROP 2 LAST CDS_LIB pure_quanta_power
J 0
(-4050 1200);
DISPLAY INVISIBLE (-4050 1200);
FORCEPROP 1 LAST PATH I35
J 0
(-3975 1200);
DISPLAY 0.872340 (-3975 1200);
PAINT AQUA (-3975 1200);
DISPLAY INVISIBLE (-3975 1200);
FORCEADD UNIVERSAL_GND..1
(-4100 2000);
FORCEPROP 3 LASTPIN (-4100 2050) SIG_NAME DELTA_L_GND_1\g
J 0
(-4090 2060);
DISPLAY 0.659574 (-4090 2060);
PAINT MONO (-4090 2060);
DISPLAY INVISIBLE (-4090 2060);
FORCEPROP 1 LAST HDL_POWER DELTA_L_GND_1
J 1
(-4075 1925);
DISPLAY 0.872340 (-4075 1925);
PAINT GREEN (-4075 1925);
FORCEPROP 2 LAST CDS_LIB pure_quanta_power
J 0
(-4100 2000);
DISPLAY INVISIBLE (-4100 2000);
FORCEPROP 1 LAST PATH I37
J 0
(-4025 2000);
DISPLAY 0.872340 (-4025 2000);
PAINT AQUA (-4025 2000);
DISPLAY INVISIBLE (-4025 2000);
FORCEADD UNIVERSAL_GND..1
(-4100 2775);
FORCEPROP 3 LASTPIN (-4100 2825) SIG_NAME DELTA_L_GND_1\g
J 0
(-4090 2835);
DISPLAY 0.659574 (-4090 2835);
PAINT MONO (-4090 2835);
DISPLAY INVISIBLE (-4090 2835);
FORCEPROP 1 LAST HDL_POWER DELTA_L_GND_1
J 1
(-4075 2700);
DISPLAY 0.872340 (-4075 2700);
PAINT GREEN (-4075 2700);
FORCEPROP 2 LAST CDS_LIB pure_quanta_power
J 0
(-4100 2775);
DISPLAY INVISIBLE (-4100 2775);
FORCEPROP 1 LAST PATH I38
J 0
(-4025 2775);
DISPLAY 0.872340 (-4025 2775);
PAINT AQUA (-4025 2775);
DISPLAY INVISIBLE (-4025 2775);
FORCEADD UNIVERSAL_GND..1
(-8125 4125);
FORCEPROP 3 LASTPIN (-8125 4175) SIG_NAME DELTA_L_GND_1\g
J 0
(-8115 4185);
DISPLAY 0.659574 (-8115 4185);
PAINT MONO (-8115 4185);
DISPLAY INVISIBLE (-8115 4185);
FORCEPROP 1 LAST HDL_POWER DELTA_L_GND_1
J 1
(-8100 4050);
DISPLAY 0.872340 (-8100 4050);
PAINT GREEN (-8100 4050);
FORCEPROP 2 LAST CDS_LIB pure_quanta_power
J 0
(-8125 4125);
DISPLAY INVISIBLE (-8125 4125);
FORCEPROP 1 LAST PATH I4
J 0
(-8050 4125);
DISPLAY 0.872340 (-8050 4125);
PAINT AQUA (-8050 4125);
DISPLAY INVISIBLE (-8050 4125);
FORCEADD UNIVERSAL_GND..1
(-4100 3425);
FORCEPROP 3 LASTPIN (-4100 3475) SIG_NAME DELTA_L_GND_1\g
J 0
(-4090 3485);
DISPLAY 0.659574 (-4090 3485);
PAINT MONO (-4090 3485);
DISPLAY INVISIBLE (-4090 3485);
FORCEPROP 1 LAST HDL_POWER DELTA_L_GND_1
J 1
(-4075 3350);
DISPLAY 0.872340 (-4075 3350);
PAINT GREEN (-4075 3350);
FORCEPROP 2 LAST CDS_LIB pure_quanta_power
J 0
(-4100 3425);
DISPLAY INVISIBLE (-4100 3425);
FORCEPROP 1 LAST PATH I40
J 0
(-4025 3425);
DISPLAY 0.872340 (-4025 3425);
PAINT AQUA (-4025 3425);
DISPLAY INVISIBLE (-4025 3425);
FORCEADD UNIVERSAL_GND..1
(-4050 4150);
FORCEPROP 3 LASTPIN (-4050 4200) SIG_NAME DELTA_L_GND_1\g
J 0
(-4040 4210);
DISPLAY 0.659574 (-4040 4210);
PAINT MONO (-4040 4210);
DISPLAY INVISIBLE (-4040 4210);
FORCEPROP 1 LAST HDL_POWER DELTA_L_GND_1
J 1
(-4025 4075);
DISPLAY 0.872340 (-4025 4075);
PAINT GREEN (-4025 4075);
FORCEPROP 2 LAST CDS_LIB pure_quanta_power
J 0
(-4050 4150);
DISPLAY INVISIBLE (-4050 4150);
FORCEPROP 1 LAST PATH I42
J 0
(-3975 4150);
DISPLAY 0.872340 (-3975 4150);
PAINT AQUA (-3975 4150);
DISPLAY INVISIBLE (-3975 4150);
FORCEADD UNIVERSAL_GND..1
(-1125 600);
FORCEPROP 3 LASTPIN (-1125 650) SIG_NAME DELTA_L_GND_1\g
J 0
(-1115 660);
DISPLAY 0.659574 (-1115 660);
PAINT MONO (-1115 660);
DISPLAY INVISIBLE (-1115 660);
FORCEPROP 1 LAST HDL_POWER DELTA_L_GND_1
J 1
(-1100 525);
DISPLAY 0.872340 (-1100 525);
PAINT GREEN (-1100 525);
FORCEPROP 2 LAST CDS_LIB pure_quanta_power
J 0
(-1125 600);
DISPLAY INVISIBLE (-1125 600);
FORCEPROP 1 LAST PATH I45
J 0
(-1050 600);
DISPLAY 0.872340 (-1050 600);
PAINT AQUA (-1050 600);
DISPLAY INVISIBLE (-1050 600);
FORCEADD UNIVERSAL_GND..1
(-1025 1375);
FORCEPROP 3 LASTPIN (-1025 1425) SIG_NAME DELTA_L_GND_1\g
J 0
(-1015 1435);
DISPLAY 0.659574 (-1015 1435);
PAINT MONO (-1015 1435);
DISPLAY INVISIBLE (-1015 1435);
FORCEPROP 1 LAST HDL_POWER DELTA_L_GND_1
J 1
(-1000 1300);
DISPLAY 0.872340 (-1000 1300);
PAINT GREEN (-1000 1300);
FORCEPROP 2 LAST CDS_LIB pure_quanta_power
J 0
(-1025 1375);
DISPLAY INVISIBLE (-1025 1375);
FORCEPROP 1 LAST PATH I48
J 0
(-950 1375);
DISPLAY 0.872340 (-950 1375);
PAINT AQUA (-950 1375);
DISPLAY INVISIBLE (-950 1375);
FORCEADD UNIVERSAL_GND..1
(-1025 2025);
FORCEPROP 3 LASTPIN (-1025 2075) SIG_NAME DELTA_L_GND_1\g
J 0
(-1015 2085);
DISPLAY 0.659574 (-1015 2085);
PAINT MONO (-1015 2085);
DISPLAY INVISIBLE (-1015 2085);
FORCEPROP 1 LAST HDL_POWER DELTA_L_GND_1
J 1
(-1000 1950);
DISPLAY 0.872340 (-1000 1950);
PAINT GREEN (-1000 1950);
FORCEPROP 2 LAST CDS_LIB pure_quanta_power
J 0
(-1025 2025);
DISPLAY INVISIBLE (-1025 2025);
FORCEPROP 1 LAST PATH I49
J 0
(-950 2025);
DISPLAY 0.872340 (-950 2025);
PAINT AQUA (-950 2025);
DISPLAY INVISIBLE (-950 2025);
FORCEADD UNIVERSAL_GND..1
(-8125 4875);
FORCEPROP 3 LASTPIN (-8125 4925) SIG_NAME DELTA_L_GND_1\g
J 0
(-8115 4935);
DISPLAY 0.659574 (-8115 4935);
PAINT MONO (-8115 4935);
DISPLAY INVISIBLE (-8115 4935);
FORCEPROP 1 LAST HDL_POWER DELTA_L_GND_1
J 1
(-8100 4800);
DISPLAY 0.872340 (-8100 4800);
PAINT GREEN (-8100 4800);
FORCEPROP 2 LAST CDS_LIB pure_quanta_power
J 0
(-8125 4875);
DISPLAY INVISIBLE (-8125 4875);
FORCEPROP 1 LAST PATH I5
J 0
(-8050 4875);
DISPLAY 0.872340 (-8050 4875);
PAINT AQUA (-8050 4875);
DISPLAY INVISIBLE (-8050 4875);
FORCEADD UNIVERSAL_GND..1
(-1075 2750);
FORCEPROP 3 LASTPIN (-1075 2800) SIG_NAME DELTA_L_GND_1\g
J 0
(-1065 2810);
DISPLAY 0.659574 (-1065 2810);
PAINT MONO (-1065 2810);
DISPLAY INVISIBLE (-1065 2810);
FORCEPROP 1 LAST HDL_POWER DELTA_L_GND_1
J 1
(-1050 2675);
DISPLAY 0.872340 (-1050 2675);
PAINT GREEN (-1050 2675);
FORCEPROP 2 LAST CDS_LIB pure_quanta_power
J 0
(-1075 2750);
DISPLAY INVISIBLE (-1075 2750);
FORCEPROP 1 LAST PATH I51
J 0
(-1000 2750);
DISPLAY 0.872340 (-1000 2750);
PAINT AQUA (-1000 2750);
DISPLAY INVISIBLE (-1000 2750);
FORCEADD UNIVERSAL_GND..1
(-1075 3425);
FORCEPROP 3 LASTPIN (-1075 3475) SIG_NAME DELTA_L_GND_1\g
J 0
(-1065 3485);
DISPLAY 0.659574 (-1065 3485);
PAINT MONO (-1065 3485);
DISPLAY INVISIBLE (-1065 3485);
FORCEPROP 1 LAST HDL_POWER DELTA_L_GND_1
J 1
(-1050 3350);
DISPLAY 0.872340 (-1050 3350);
PAINT GREEN (-1050 3350);
FORCEPROP 2 LAST CDS_LIB pure_quanta_power
J 0
(-1075 3425);
DISPLAY INVISIBLE (-1075 3425);
FORCEPROP 1 LAST PATH I54
J 0
(-1000 3425);
DISPLAY 0.872340 (-1000 3425);
PAINT AQUA (-1000 3425);
DISPLAY INVISIBLE (-1000 3425);
FORCEADD UNIVERSAL_GND..1
(-1050 4125);
FORCEPROP 3 LASTPIN (-1050 4175) SIG_NAME DELTA_L_GND_1\g
J 0
(-1040 4185);
DISPLAY 0.659574 (-1040 4185);
PAINT MONO (-1040 4185);
DISPLAY INVISIBLE (-1040 4185);
FORCEPROP 1 LAST HDL_POWER DELTA_L_GND_1
J 1
(-1025 4050);
DISPLAY 0.872340 (-1025 4050);
PAINT GREEN (-1025 4050);
FORCEPROP 2 LAST CDS_LIB pure_quanta_power
J 0
(-1050 4125);
DISPLAY INVISIBLE (-1050 4125);
FORCEPROP 1 LAST PATH I55
J 0
(-975 4125);
DISPLAY 0.872340 (-975 4125);
PAINT AQUA (-975 4125);
DISPLAY INVISIBLE (-975 4125);
FORCEADD UNIVERSAL_GND..1
(-4075 4875);
FORCEPROP 3 LASTPIN (-4075 4925) SIG_NAME DELTA_L_GND_1\g
J 0
(-4065 4935);
DISPLAY 0.659574 (-4065 4935);
PAINT MONO (-4065 4935);
DISPLAY INVISIBLE (-4065 4935);
FORCEPROP 1 LAST HDL_POWER DELTA_L_GND_1
J 1
(-4050 4800);
DISPLAY 0.872340 (-4050 4800);
PAINT GREEN (-4050 4800);
FORCEPROP 2 LAST CDS_LIB pure_quanta_power
J 0
(-4075 4875);
DISPLAY INVISIBLE (-4075 4875);
FORCEPROP 1 LAST PATH I56
J 0
(-4000 4875);
DISPLAY 0.872340 (-4000 4875);
PAINT AQUA (-4000 4875);
DISPLAY INVISIBLE (-4000 4875);
FORCEADD UNIVERSAL_GND..1
(-4075 5675);
FORCEPROP 3 LASTPIN (-4075 5725) SIG_NAME DELTA_L_GND_1\g
J 0
(-4065 5735);
DISPLAY 0.659574 (-4065 5735);
PAINT MONO (-4065 5735);
DISPLAY INVISIBLE (-4065 5735);
FORCEPROP 1 LAST HDL_POWER DELTA_L_GND_1
J 1
(-4050 5600);
DISPLAY 0.872340 (-4050 5600);
PAINT GREEN (-4050 5600);
FORCEPROP 2 LAST CDS_LIB pure_quanta_power
J 0
(-4075 5675);
DISPLAY INVISIBLE (-4075 5675);
FORCEPROP 1 LAST PATH I58
J 0
(-4000 5675);
DISPLAY 0.872340 (-4000 5675);
PAINT AQUA (-4000 5675);
DISPLAY INVISIBLE (-4000 5675);
FORCEADD UNIVERSAL_GND..1
(-8125 5700);
FORCEPROP 3 LASTPIN (-8125 5750) SIG_NAME DELTA_L_GND_1\g
J 0
(-8115 5760);
DISPLAY 0.659574 (-8115 5760);
PAINT MONO (-8115 5760);
DISPLAY INVISIBLE (-8115 5760);
FORCEPROP 1 LAST HDL_POWER DELTA_L_GND_1
J 1
(-8100 5625);
DISPLAY 0.872340 (-8100 5625);
PAINT GREEN (-8100 5625);
FORCEPROP 2 LAST CDS_LIB pure_quanta_power
J 0
(-8125 5700);
DISPLAY INVISIBLE (-8125 5700);
FORCEPROP 1 LAST PATH I6
J 0
(-8050 5700);
DISPLAY 0.872340 (-8050 5700);
PAINT AQUA (-8050 5700);
DISPLAY INVISIBLE (-8050 5700);
FORCEADD UNIVERSAL_GND..1
(-1200 4875);
FORCEPROP 3 LASTPIN (-1200 4925) SIG_NAME DELTA_L_GND_1\g
J 0
(-1190 4935);
DISPLAY 0.659574 (-1190 4935);
PAINT MONO (-1190 4935);
DISPLAY INVISIBLE (-1190 4935);
FORCEPROP 1 LAST HDL_POWER DELTA_L_GND_1
J 1
(-1175 4800);
DISPLAY 0.872340 (-1175 4800);
PAINT GREEN (-1175 4800);
FORCEPROP 2 LAST CDS_LIB pure_quanta_power
J 0
(-1200 4875);
DISPLAY INVISIBLE (-1200 4875);
FORCEPROP 1 LAST PATH I61
J 0
(-1125 4875);
DISPLAY 0.872340 (-1125 4875);
PAINT AQUA (-1125 4875);
DISPLAY INVISIBLE (-1125 4875);
FORCEADD UNIVERSAL_GND..1
(-975 5675);
FORCEPROP 3 LASTPIN (-975 5725) SIG_NAME DELTA_L_GND_1\g
J 0
(-965 5735);
DISPLAY 0.659574 (-965 5735);
PAINT MONO (-965 5735);
DISPLAY INVISIBLE (-965 5735);
FORCEPROP 1 LAST HDL_POWER DELTA_L_GND_1
J 1
(-950 5600);
DISPLAY 0.872340 (-950 5600);
PAINT GREEN (-950 5600);
FORCEPROP 2 LAST CDS_LIB pure_quanta_power
J 0
(-975 5675);
DISPLAY INVISIBLE (-975 5675);
FORCEPROP 1 LAST PATH I63
J 0
(-900 5675);
DISPLAY 0.872340 (-900 5675);
PAINT AQUA (-900 5675);
DISPLAY INVISIBLE (-900 5675);
FORCEADD PICOPROBE_BXA..1
(-7650 5775);
FORCEPROP 1 LAST LOCATION J63
J 0
(-7804 5979);
DISPLAY 0.723404 (-7804 5979);
PAINT GREEN (-7804 5979);
FORCEPROP 2 LAST SEC 1
J 0
(-7800 6125);
DISPLAY 0.680851 (-7800 6125);
PAINT MONO (-7800 6125);
DISPLAY INVISIBLE (-7800 6125);
FORCEPROP 2 LASTPIN (-7350 5775) $PN 1
J 0
(-7340 5785);
DISPLAY 0.680851 (-7340 5785);
PAINT MONO (-7340 5785);
FORCEPROP 2 LASTPIN (-7350 5825) $PN 2
J 0
(-7340 5835);
DISPLAY 0.680851 (-7340 5835);
PAINT MONO (-7340 5835);
FORCEPROP 2 LASTPIN (-7950 5825) $PN 3
J 2
(-7960 5835);
DISPLAY 0.680851 (-7960 5835);
PAINT MONO (-7960 5835);
FORCEPROP 1 LAST MATERIAL EMPTY
J 0
(-7804 5880);
DISPLAY 0.723404 (-7804 5880);
PAINT GREEN (-7804 5880);
FORCEPROP 2 LAST VALUE DELTA-L 4.0
J 0
(-7800 6025);
DISPLAY 0.680851 (-7800 6025);
FORCEPROP 2 LAST PART_TYPE SMLF
J 0
(-7800 6075);
DISPLAY 0.680851 (-7800 6075);
FORCEPROP 1 LAST NEEDS_NO_SIZE TRUE
J 0
(-7650 5775);
DISPLAY 0.723404 (-7650 5775);
PAINT GREEN (-7650 5775);
DISPLAY INVISIBLE (-7650 5775);
FORCEPROP 2 LAST SEC_TYPE 
J 0
(-7800 6125);
DISPLAY 0.680851 (-7800 6125);
DISPLAY INVISIBLE (-7800 6125);
FORCEPROP 2 LAST CDS_LIB pure_quanta
J 0
(-7650 5775);
DISPLAY INVISIBLE (-7650 5775);
FORCEPROP 1 LAST CDS_LMAN_SYM_OUTLINE -150,100,150,-100
J 0
(-7650 5775);
DISPLAY 0.468085 (-7650 5775);
PAINT GREEN (-7650 5775);
DISPLAY INVISIBLE (-7650 5775);
FORCEPROP 1 LAST PATH I65
J 0
(-7650 5775);
DISPLAY 0.723404 (-7650 5775);
PAINT GREEN (-7650 5775);
DISPLAY INVISIBLE (-7650 5775);
FORCEPROP 1 LAST PART_NUMBER TP33
J 0
(-7800 5925);
DISPLAY 0.723404 (-7800 5925);
PAINT GREEN (-7800 5925);
DISPLAY INVISIBLE (-7800 5925);
FORCEADD PICOPROBE_BXA..1
R 4
(-5875 5825);
FORCEPROP 1 LAST LOCATION J8069
R 2
J 0
(-5725 5625);
DISPLAY 0.723404 (-5725 5625);
PAINT GREEN (-5725 5625);
FORCEPROP 2 LAST SEC 1
J 0
(-5575 5950);
DISPLAY 0.680851 (-5575 5950);
PAINT MONO (-5575 5950);
DISPLAY INVISIBLE (-5575 5950);
FORCEPROP 2 LASTPIN (-6175 5825) $PN 1
J 2
(-6185 5835);
DISPLAY 0.680851 (-6185 5835);
PAINT MONO (-6185 5835);
FORCEPROP 2 LASTPIN (-6175 5775) $PN 2
J 2
(-6185 5785);
DISPLAY 0.680851 (-6185 5785);
PAINT MONO (-6185 5785);
FORCEPROP 2 LASTPIN (-5575 5775) $PN 3
J 0
(-5565 5785);
DISPLAY 0.680851 (-5565 5785);
PAINT MONO (-5565 5785);
FORCEPROP 1 LAST MATERIAL EMPTY
R 2
J 0
(-5721 5720);
DISPLAY 0.723404 (-5721 5720);
PAINT GREEN (-5721 5720);
FORCEPROP 2 LAST VALUE DELTA-L 4.0
R 2
J 0
(-5675 6000);
DISPLAY 0.680851 (-5675 6000);
FORCEPROP 2 LAST PART_TYPE SMLF
R 2
J 0
(-5675 5975);
DISPLAY 0.680851 (-5675 5975);
FORCEPROP 1 LAST NEEDS_NO_SIZE TRUE
R 2
J 0
(-5875 5825);
DISPLAY 0.723404 (-5875 5825);
PAINT GREEN (-5875 5825);
DISPLAY INVISIBLE (-5875 5825);
FORCEPROP 2 LAST SEC_TYPE 
J 0
(-5575 5950);
DISPLAY 0.680851 (-5575 5950);
DISPLAY INVISIBLE (-5575 5950);
FORCEPROP 1 LAST CDS_LMAN_SYM_OUTLINE -150,100,150,-100
R 2
J 0
(-5875 5825);
DISPLAY 0.468085 (-5875 5825);
PAINT GREEN (-5875 5825);
DISPLAY INVISIBLE (-5875 5825);
FORCEPROP 2 LAST CDS_LIB pure_quanta
R 2
J 0
(-5875 5825);
DISPLAY INVISIBLE (-5875 5825);
FORCEPROP 1 LAST PATH I66
R 2
J 0
(-5875 5825);
DISPLAY 0.723404 (-5875 5825);
PAINT GREEN (-5875 5825);
DISPLAY INVISIBLE (-5875 5825);
FORCEPROP 1 LAST PART_NUMBER TP33
R 2
J 0
(-5725 5675);
DISPLAY 0.723404 (-5725 5675);
PAINT GREEN (-5725 5675);
DISPLAY INVISIBLE (-5725 5675);
FORCEADD PICOPROBE_BXA..1
(-7650 5050);
FORCEPROP 1 LAST LOCATION J64
J 0
(-7800 5350);
DISPLAY 0.723404 (-7800 5350);
PAINT GREEN (-7800 5350);
FORCEPROP 2 LAST SEC 1
J 0
(-7800 5400);
DISPLAY 0.680851 (-7800 5400);
PAINT MONO (-7800 5400);
DISPLAY INVISIBLE (-7800 5400);
FORCEPROP 2 LASTPIN (-7350 5050) $PN 1
J 0
(-7340 5060);
DISPLAY 0.680851 (-7340 5060);
PAINT MONO (-7340 5060);
FORCEPROP 2 LASTPIN (-7350 5100) $PN 2
J 0
(-7340 5110);
DISPLAY 0.680851 (-7340 5110);
PAINT MONO (-7340 5110);
FORCEPROP 2 LASTPIN (-7950 5100) $PN 3
J 2
(-7960 5110);
DISPLAY 0.680851 (-7960 5110);
PAINT MONO (-7960 5110);
FORCEPROP 2 LAST VALUE DELTA-L 4.0
J 0
(-7800 5250);
DISPLAY 0.680851 (-7800 5250);
FORCEPROP 2 LAST PART_TYPE SMLF
J 0
(-7800 5300);
DISPLAY 0.680851 (-7800 5300);
FORCEPROP 1 LAST MATERIAL EMPTY
J 0
(-7804 5155);
DISPLAY 0.723404 (-7804 5155);
PAINT GREEN (-7804 5155);
FORCEPROP 2 LAST SEC_TYPE 
J 0
(-7800 5400);
DISPLAY 0.680851 (-7800 5400);
DISPLAY INVISIBLE (-7800 5400);
FORCEPROP 2 LAST CDS_LIB pure_quanta
J 0
(-7650 5050);
DISPLAY INVISIBLE (-7650 5050);
FORCEPROP 1 LAST CDS_LMAN_SYM_OUTLINE -150,100,150,-100
J 0
(-7650 5050);
DISPLAY 0.468085 (-7650 5050);
PAINT GREEN (-7650 5050);
DISPLAY INVISIBLE (-7650 5050);
FORCEPROP 1 LAST NEEDS_NO_SIZE TRUE
J 0
(-7650 5050);
DISPLAY 0.723404 (-7650 5050);
PAINT GREEN (-7650 5050);
DISPLAY INVISIBLE (-7650 5050);
FORCEPROP 1 LAST PATH I67
J 0
(-7650 5050);
DISPLAY 0.723404 (-7650 5050);
PAINT GREEN (-7650 5050);
DISPLAY INVISIBLE (-7650 5050);
FORCEPROP 1 LAST PART_NUMBER TP33
J 0
(-7800 5200);
DISPLAY 0.723404 (-7800 5200);
PAINT GREEN (-7800 5200);
DISPLAY INVISIBLE (-7800 5200);
FORCEADD PICOPROBE_BXA..1
R 4
(-5875 5100);
FORCEPROP 1 LAST LOCATION J70
R 2
J 0
(-5725 4900);
DISPLAY 0.723404 (-5725 4900);
PAINT GREEN (-5725 4900);
FORCEPROP 2 LAST SEC 1
J 0
(-5575 5225);
DISPLAY 0.680851 (-5575 5225);
PAINT MONO (-5575 5225);
DISPLAY INVISIBLE (-5575 5225);
FORCEPROP 2 LASTPIN (-6175 5100) $PN 1
J 2
(-6185 5110);
DISPLAY 0.680851 (-6185 5110);
PAINT MONO (-6185 5110);
FORCEPROP 2 LASTPIN (-6175 5050) $PN 2
J 2
(-6185 5060);
DISPLAY 0.680851 (-6185 5060);
PAINT MONO (-6185 5060);
FORCEPROP 2 LASTPIN (-5575 5050) $PN 3
J 0
(-5565 5060);
DISPLAY 0.680851 (-5565 5060);
PAINT MONO (-5565 5060);
FORCEPROP 2 LAST VALUE DELTA-L 4.0
R 2
J 0
(-5675 5275);
DISPLAY 0.680851 (-5675 5275);
FORCEPROP 1 LAST MATERIAL EMPTY
R 2
J 0
(-5721 4995);
DISPLAY 0.723404 (-5721 4995);
PAINT GREEN (-5721 4995);
FORCEPROP 2 LAST PART_TYPE SMLF
R 2
J 0
(-5675 5250);
DISPLAY 0.680851 (-5675 5250);
FORCEPROP 2 LAST CDS_LIB pure_quanta
J 0
(-5875 5100);
DISPLAY INVISIBLE (-5875 5100);
FORCEPROP 1 LAST CDS_LMAN_SYM_OUTLINE -150,100,150,-100
R 2
J 0
(-5875 5100);
DISPLAY 0.468085 (-5875 5100);
PAINT GREEN (-5875 5100);
DISPLAY INVISIBLE (-5875 5100);
FORCEPROP 2 LAST SEC_TYPE 
J 0
(-5575 5225);
DISPLAY 0.680851 (-5575 5225);
DISPLAY INVISIBLE (-5575 5225);
FORCEPROP 1 LAST NEEDS_NO_SIZE TRUE
R 2
J 0
(-5875 5100);
DISPLAY 0.723404 (-5875 5100);
PAINT GREEN (-5875 5100);
DISPLAY INVISIBLE (-5875 5100);
FORCEPROP 1 LAST PATH I68
R 2
J 0
(-5875 5100);
DISPLAY 0.723404 (-5875 5100);
PAINT GREEN (-5875 5100);
DISPLAY INVISIBLE (-5875 5100);
FORCEPROP 1 LAST PART_NUMBER TP33
R 2
J 0
(-5725 4950);
DISPLAY 0.723404 (-5725 4950);
PAINT GREEN (-5725 4950);
DISPLAY INVISIBLE (-5725 4950);
FORCEADD PICOPROBE_BXA..1
(-7675 4300);
FORCEPROP 1 LAST LOCATION J65
J 0
(-7825 4600);
DISPLAY 0.723404 (-7825 4600);
PAINT GREEN (-7825 4600);
FORCEPROP 2 LAST SEC 1
J 0
(-7825 4650);
DISPLAY 0.680851 (-7825 4650);
PAINT MONO (-7825 4650);
DISPLAY INVISIBLE (-7825 4650);
FORCEPROP 2 LASTPIN (-7375 4300) $PN 1
J 0
(-7365 4310);
DISPLAY 0.680851 (-7365 4310);
PAINT MONO (-7365 4310);
FORCEPROP 2 LASTPIN (-7375 4350) $PN 2
J 0
(-7365 4360);
DISPLAY 0.680851 (-7365 4360);
PAINT MONO (-7365 4360);
FORCEPROP 2 LASTPIN (-7975 4350) $PN 3
J 2
(-7985 4360);
DISPLAY 0.680851 (-7985 4360);
PAINT MONO (-7985 4360);
FORCEPROP 1 LAST MATERIAL EMPTY
J 0
(-7829 4405);
DISPLAY 0.723404 (-7829 4405);
PAINT GREEN (-7829 4405);
FORCEPROP 2 LAST VALUE DELTA-L 4.0
J 0
(-7825 4500);
DISPLAY 0.680851 (-7825 4500);
FORCEPROP 2 LAST PART_TYPE SMLF
J 0
(-7825 4550);
DISPLAY 0.680851 (-7825 4550);
FORCEPROP 1 LAST NEEDS_NO_SIZE TRUE
J 0
(-7675 4300);
DISPLAY 0.723404 (-7675 4300);
PAINT GREEN (-7675 4300);
DISPLAY INVISIBLE (-7675 4300);
FORCEPROP 2 LAST SEC_TYPE 
J 0
(-7825 4650);
DISPLAY 0.680851 (-7825 4650);
DISPLAY INVISIBLE (-7825 4650);
FORCEPROP 1 LAST CDS_LMAN_SYM_OUTLINE -150,100,150,-100
J 0
(-7675 4300);
DISPLAY 0.468085 (-7675 4300);
PAINT GREEN (-7675 4300);
DISPLAY INVISIBLE (-7675 4300);
FORCEPROP 2 LAST CDS_LIB pure_quanta
J 0
(-7675 4300);
DISPLAY INVISIBLE (-7675 4300);
FORCEPROP 1 LAST PATH I69
J 0
(-7675 4300);
DISPLAY 0.723404 (-7675 4300);
PAINT GREEN (-7675 4300);
DISPLAY INVISIBLE (-7675 4300);
FORCEPROP 1 LAST PART_NUMBER TP33
J 0
(-7825 4450);
DISPLAY 0.723404 (-7825 4450);
PAINT GREEN (-7825 4450);
DISPLAY INVISIBLE (-7825 4450);
FORCEADD UNIVERSAL_GND..1
(-8100 1325);
FORCEPROP 3 LASTPIN (-8100 1375) SIG_NAME DELTA_L_GND_1\g
J 0
(-8090 1385);
DISPLAY 0.659574 (-8090 1385);
PAINT MONO (-8090 1385);
DISPLAY INVISIBLE (-8090 1385);
FORCEPROP 1 LAST HDL_POWER DELTA_L_GND_1
J 1
(-8075 1250);
DISPLAY 0.872340 (-8075 1250);
PAINT GREEN (-8075 1250);
FORCEPROP 2 LAST CDS_LIB pure_quanta_power
J 0
(-8100 1325);
DISPLAY INVISIBLE (-8100 1325);
FORCEPROP 1 LAST PATH I7
J 0
(-8025 1325);
DISPLAY 0.872340 (-8025 1325);
PAINT AQUA (-8025 1325);
DISPLAY INVISIBLE (-8025 1325);
FORCEADD PICOPROBE_BXA..1
R 4
(-5875 4350);
FORCEPROP 1 LAST LOCATION J71
R 2
J 0
(-5725 4150);
DISPLAY 0.723404 (-5725 4150);
PAINT GREEN (-5725 4150);
FORCEPROP 2 LAST SEC 1
J 0
(-5575 4475);
DISPLAY 0.680851 (-5575 4475);
PAINT MONO (-5575 4475);
DISPLAY INVISIBLE (-5575 4475);
FORCEPROP 2 LASTPIN (-6175 4350) $PN 1
J 2
(-6185 4360);
DISPLAY 0.680851 (-6185 4360);
PAINT MONO (-6185 4360);
FORCEPROP 2 LASTPIN (-6175 4300) $PN 2
J 2
(-6185 4310);
DISPLAY 0.680851 (-6185 4310);
PAINT MONO (-6185 4310);
FORCEPROP 2 LASTPIN (-5575 4300) $PN 3
J 0
(-5565 4310);
DISPLAY 0.680851 (-5565 4310);
PAINT MONO (-5565 4310);
FORCEPROP 1 LAST MATERIAL EMPTY
R 2
J 0
(-5721 4245);
DISPLAY 0.723404 (-5721 4245);
PAINT GREEN (-5721 4245);
FORCEPROP 2 LAST VALUE DELTA-L 4.0
R 2
J 0
(-5675 4525);
DISPLAY 0.680851 (-5675 4525);
FORCEPROP 2 LAST PART_TYPE SMLF
R 2
J 0
(-5675 4500);
DISPLAY 0.680851 (-5675 4500);
FORCEPROP 1 LAST NEEDS_NO_SIZE TRUE
R 2
J 0
(-5875 4350);
DISPLAY 0.723404 (-5875 4350);
PAINT GREEN (-5875 4350);
DISPLAY INVISIBLE (-5875 4350);
FORCEPROP 2 LAST SEC_TYPE 
J 0
(-5575 4475);
DISPLAY 0.680851 (-5575 4475);
DISPLAY INVISIBLE (-5575 4475);
FORCEPROP 1 LAST CDS_LMAN_SYM_OUTLINE -150,100,150,-100
R 2
J 0
(-5875 4350);
DISPLAY 0.468085 (-5875 4350);
PAINT GREEN (-5875 4350);
DISPLAY INVISIBLE (-5875 4350);
FORCEPROP 2 LAST CDS_LIB pure_quanta
J 0
(-5875 4350);
DISPLAY INVISIBLE (-5875 4350);
FORCEPROP 1 LAST PATH I70
R 2
J 0
(-5875 4350);
DISPLAY 0.723404 (-5875 4350);
PAINT GREEN (-5875 4350);
DISPLAY INVISIBLE (-5875 4350);
FORCEPROP 1 LAST PART_NUMBER TP33
R 2
J 0
(-5725 4200);
DISPLAY 0.723404 (-5725 4200);
PAINT GREEN (-5725 4200);
DISPLAY INVISIBLE (-5725 4200);
FORCEADD PICOPROBE_BXA..1
(-7675 3575);
FORCEPROP 1 LAST LOCATION J66
J 0
(-7825 3875);
DISPLAY 0.723404 (-7825 3875);
PAINT GREEN (-7825 3875);
FORCEPROP 2 LAST SEC 1
J 0
(-7825 3925);
DISPLAY 0.680851 (-7825 3925);
PAINT MONO (-7825 3925);
DISPLAY INVISIBLE (-7825 3925);
FORCEPROP 2 LASTPIN (-7375 3575) $PN 1
J 0
(-7365 3585);
DISPLAY 0.680851 (-7365 3585);
PAINT MONO (-7365 3585);
FORCEPROP 2 LASTPIN (-7375 3625) $PN 2
J 0
(-7365 3635);
DISPLAY 0.680851 (-7365 3635);
PAINT MONO (-7365 3635);
FORCEPROP 2 LASTPIN (-7975 3625) $PN 3
J 2
(-7985 3635);
DISPLAY 0.680851 (-7985 3635);
PAINT MONO (-7985 3635);
FORCEPROP 2 LAST VALUE DELTA-L 4.0
J 0
(-7825 3775);
DISPLAY 0.680851 (-7825 3775);
FORCEPROP 1 LAST MATERIAL EMPTY
J 0
(-7829 3680);
DISPLAY 0.723404 (-7829 3680);
PAINT GREEN (-7829 3680);
FORCEPROP 2 LAST PART_TYPE SMLF
J 0
(-7825 3825);
DISPLAY 0.680851 (-7825 3825);
FORCEPROP 2 LAST CDS_LIB pure_quanta
J 0
(-7675 3575);
DISPLAY INVISIBLE (-7675 3575);
FORCEPROP 1 LAST CDS_LMAN_SYM_OUTLINE -150,100,150,-100
J 0
(-7675 3575);
DISPLAY 0.468085 (-7675 3575);
PAINT GREEN (-7675 3575);
DISPLAY INVISIBLE (-7675 3575);
FORCEPROP 2 LAST SEC_TYPE 
J 0
(-7825 3925);
DISPLAY 0.680851 (-7825 3925);
DISPLAY INVISIBLE (-7825 3925);
FORCEPROP 1 LAST NEEDS_NO_SIZE TRUE
J 0
(-7675 3575);
DISPLAY 0.723404 (-7675 3575);
PAINT GREEN (-7675 3575);
DISPLAY INVISIBLE (-7675 3575);
FORCEPROP 1 LAST PATH I71
J 0
(-7675 3575);
DISPLAY 0.723404 (-7675 3575);
PAINT GREEN (-7675 3575);
DISPLAY INVISIBLE (-7675 3575);
FORCEPROP 1 LAST PART_NUMBER TP33
J 0
(-7825 3725);
DISPLAY 0.723404 (-7825 3725);
PAINT GREEN (-7825 3725);
DISPLAY INVISIBLE (-7825 3725);
FORCEADD PICOPROBE_BXA..1
R 4
(-5875 3625);
FORCEPROP 1 LAST LOCATION J72
R 2
J 0
(-5725 3425);
DISPLAY 0.723404 (-5725 3425);
PAINT GREEN (-5725 3425);
FORCEPROP 2 LAST SEC 1
J 0
(-5575 3750);
DISPLAY 0.680851 (-5575 3750);
PAINT MONO (-5575 3750);
DISPLAY INVISIBLE (-5575 3750);
FORCEPROP 2 LASTPIN (-6175 3625) $PN 1
J 2
(-6185 3635);
DISPLAY 0.680851 (-6185 3635);
PAINT MONO (-6185 3635);
FORCEPROP 2 LASTPIN (-6175 3575) $PN 2
J 2
(-6185 3585);
DISPLAY 0.680851 (-6185 3585);
PAINT MONO (-6185 3585);
FORCEPROP 2 LASTPIN (-5575 3575) $PN 3
J 0
(-5565 3585);
DISPLAY 0.680851 (-5565 3585);
PAINT MONO (-5565 3585);
FORCEPROP 1 LAST MATERIAL EMPTY
R 2
J 0
(-5721 3520);
DISPLAY 0.723404 (-5721 3520);
PAINT GREEN (-5721 3520);
FORCEPROP 2 LAST VALUE DELTA-L 4.0
R 2
J 0
(-5675 3800);
DISPLAY 0.680851 (-5675 3800);
FORCEPROP 2 LAST PART_TYPE SMLF
R 2
J 0
(-5675 3775);
DISPLAY 0.680851 (-5675 3775);
FORCEPROP 2 LAST CDS_LIB pure_quanta
J 0
(-5875 3625);
DISPLAY INVISIBLE (-5875 3625);
FORCEPROP 1 LAST CDS_LMAN_SYM_OUTLINE -150,100,150,-100
R 2
J 0
(-5875 3625);
DISPLAY 0.468085 (-5875 3625);
PAINT GREEN (-5875 3625);
DISPLAY INVISIBLE (-5875 3625);
FORCEPROP 2 LAST SEC_TYPE 
J 0
(-5575 3750);
DISPLAY 0.680851 (-5575 3750);
DISPLAY INVISIBLE (-5575 3750);
FORCEPROP 1 LAST NEEDS_NO_SIZE TRUE
R 2
J 0
(-5875 3625);
DISPLAY 0.723404 (-5875 3625);
PAINT GREEN (-5875 3625);
DISPLAY INVISIBLE (-5875 3625);
FORCEPROP 1 LAST PATH I72
R 2
J 0
(-5875 3625);
DISPLAY 0.723404 (-5875 3625);
PAINT GREEN (-5875 3625);
DISPLAY INVISIBLE (-5875 3625);
FORCEPROP 1 LAST PART_NUMBER TP33
R 2
J 0
(-5725 3475);
DISPLAY 0.723404 (-5725 3475);
PAINT GREEN (-5725 3475);
DISPLAY INVISIBLE (-5725 3475);
FORCEADD PICOPROBE_BXA..1
(-7700 2900);
FORCEPROP 1 LAST LOCATION J8067
J 0
(-7850 3200);
DISPLAY 0.723404 (-7850 3200);
PAINT GREEN (-7850 3200);
FORCEPROP 2 LAST SEC 1
J 0
(-7850 3325);
DISPLAY 0.680851 (-7850 3325);
PAINT MONO (-7850 3325);
DISPLAY INVISIBLE (-7850 3325);
FORCEPROP 2 LASTPIN (-7400 2900) $PN 1
J 0
(-7390 2910);
DISPLAY 0.680851 (-7390 2910);
PAINT MONO (-7390 2910);
FORCEPROP 2 LASTPIN (-7400 2950) $PN 2
J 0
(-7390 2960);
DISPLAY 0.680851 (-7390 2960);
PAINT MONO (-7390 2960);
FORCEPROP 2 LASTPIN (-8000 2950) $PN 3
J 2
(-8010 2960);
DISPLAY 0.680851 (-8010 2960);
PAINT MONO (-8010 2960);
FORCEPROP 1 LAST MATERIAL EMPTY
J 0
(-7854 3005);
DISPLAY 0.723404 (-7854 3005);
PAINT GREEN (-7854 3005);
FORCEPROP 2 LAST VALUE DELTA-L 4.0
J 0
(-7850 3100);
DISPLAY 0.680851 (-7850 3100);
FORCEPROP 2 LAST PART_TYPE SMLF
J 0
(-7850 3150);
DISPLAY 0.680851 (-7850 3150);
FORCEPROP 1 LAST NEEDS_NO_SIZE TRUE
J 0
(-7700 2900);
DISPLAY 0.723404 (-7700 2900);
PAINT GREEN (-7700 2900);
DISPLAY INVISIBLE (-7700 2900);
FORCEPROP 2 LAST SEC_TYPE 
J 0
(-7850 3325);
DISPLAY 0.680851 (-7850 3325);
DISPLAY INVISIBLE (-7850 3325);
FORCEPROP 1 LAST CDS_LMAN_SYM_OUTLINE -150,100,150,-100
J 0
(-7700 2900);
DISPLAY 0.468085 (-7700 2900);
PAINT GREEN (-7700 2900);
DISPLAY INVISIBLE (-7700 2900);
FORCEPROP 2 LAST CDS_LIB pure_quanta
J 0
(-7700 2900);
DISPLAY INVISIBLE (-7700 2900);
FORCEPROP 1 LAST PATH I73
J 0
(-7700 2900);
DISPLAY 0.723404 (-7700 2900);
PAINT GREEN (-7700 2900);
DISPLAY INVISIBLE (-7700 2900);
FORCEPROP 1 LAST PART_NUMBER TP33
J 0
(-7850 3050);
DISPLAY 0.723404 (-7850 3050);
PAINT GREEN (-7850 3050);
DISPLAY INVISIBLE (-7850 3050);
FORCEADD PICOPROBE_BXA..1
R 4
(-5825 2950);
FORCEPROP 1 LAST LOCATION J73
R 2
J 0
(-5675 2750);
DISPLAY 0.723404 (-5675 2750);
PAINT GREEN (-5675 2750);
FORCEPROP 2 LAST SEC 1
J 0
(-5525 3075);
DISPLAY 0.680851 (-5525 3075);
PAINT MONO (-5525 3075);
DISPLAY INVISIBLE (-5525 3075);
FORCEPROP 2 LASTPIN (-6125 2950) $PN 1
J 2
(-6135 2960);
DISPLAY 0.680851 (-6135 2960);
PAINT MONO (-6135 2960);
FORCEPROP 2 LASTPIN (-6125 2900) $PN 2
J 2
(-6135 2910);
DISPLAY 0.680851 (-6135 2910);
PAINT MONO (-6135 2910);
FORCEPROP 2 LASTPIN (-5525 2900) $PN 3
J 0
(-5515 2910);
DISPLAY 0.680851 (-5515 2910);
PAINT MONO (-5515 2910);
FORCEPROP 2 LAST VALUE DELTA-L 4.0
R 2
J 0
(-5625 3125);
DISPLAY 0.680851 (-5625 3125);
FORCEPROP 2 LAST PART_TYPE SMLF
R 2
J 0
(-5625 3100);
DISPLAY 0.680851 (-5625 3100);
FORCEPROP 1 LAST MATERIAL EMPTY
R 2
J 0
(-5671 2845);
DISPLAY 0.723404 (-5671 2845);
PAINT GREEN (-5671 2845);
FORCEPROP 2 LAST CDS_LIB pure_quanta
J 0
(-5825 2950);
DISPLAY INVISIBLE (-5825 2950);
FORCEPROP 1 LAST CDS_LMAN_SYM_OUTLINE -150,100,150,-100
R 2
J 0
(-5825 2950);
DISPLAY 0.468085 (-5825 2950);
PAINT GREEN (-5825 2950);
DISPLAY INVISIBLE (-5825 2950);
FORCEPROP 2 LAST SEC_TYPE 
J 0
(-5525 3075);
DISPLAY 0.680851 (-5525 3075);
DISPLAY INVISIBLE (-5525 3075);
FORCEPROP 1 LAST NEEDS_NO_SIZE TRUE
R 2
J 0
(-5825 2950);
DISPLAY 0.723404 (-5825 2950);
PAINT GREEN (-5825 2950);
DISPLAY INVISIBLE (-5825 2950);
FORCEPROP 1 LAST PATH I74
R 2
J 0
(-5825 2950);
DISPLAY 0.723404 (-5825 2950);
PAINT GREEN (-5825 2950);
DISPLAY INVISIBLE (-5825 2950);
FORCEPROP 1 LAST PART_NUMBER TP33
R 2
J 0
(-5675 2800);
DISPLAY 0.723404 (-5675 2800);
PAINT GREEN (-5675 2800);
DISPLAY INVISIBLE (-5675 2800);
FORCEADD PICOPROBE_BXA..1
(-7650 2150);
FORCEPROP 1 LAST LOCATION J8068
J 0
(-7800 2450);
DISPLAY 0.723404 (-7800 2450);
PAINT GREEN (-7800 2450);
FORCEPROP 2 LAST SEC 1
J 0
(-7800 2500);
DISPLAY 0.680851 (-7800 2500);
PAINT MONO (-7800 2500);
DISPLAY INVISIBLE (-7800 2500);
FORCEPROP 2 LASTPIN (-7350 2150) $PN 1
J 0
(-7340 2160);
DISPLAY 0.680851 (-7340 2160);
PAINT MONO (-7340 2160);
FORCEPROP 2 LASTPIN (-7350 2200) $PN 2
J 0
(-7340 2210);
DISPLAY 0.680851 (-7340 2210);
PAINT MONO (-7340 2210);
FORCEPROP 2 LASTPIN (-7950 2200) $PN 3
J 2
(-7960 2210);
DISPLAY 0.680851 (-7960 2210);
PAINT MONO (-7960 2210);
FORCEPROP 2 LAST PART_TYPE SMLF
J 0
(-7800 2400);
DISPLAY 0.680851 (-7800 2400);
FORCEPROP 2 LAST VALUE DELTA-L 4.0
J 0
(-7800 2350);
DISPLAY 0.680851 (-7800 2350);
FORCEPROP 1 LAST MATERIAL EMPTY
J 0
(-7804 2255);
DISPLAY 0.723404 (-7804 2255);
PAINT GREEN (-7804 2255);
FORCEPROP 1 LAST NEEDS_NO_SIZE TRUE
J 0
(-7650 2150);
DISPLAY 0.723404 (-7650 2150);
PAINT GREEN (-7650 2150);
DISPLAY INVISIBLE (-7650 2150);
FORCEPROP 2 LAST SEC_TYPE 
J 0
(-7800 2500);
DISPLAY 0.680851 (-7800 2500);
DISPLAY INVISIBLE (-7800 2500);
FORCEPROP 1 LAST CDS_LMAN_SYM_OUTLINE -150,100,150,-100
J 0
(-7650 2150);
DISPLAY 0.468085 (-7650 2150);
PAINT GREEN (-7650 2150);
DISPLAY INVISIBLE (-7650 2150);
FORCEPROP 2 LAST CDS_LIB pure_quanta
J 0
(-7650 2150);
DISPLAY INVISIBLE (-7650 2150);
FORCEPROP 1 LAST PATH I75
J 0
(-7650 2150);
DISPLAY 0.723404 (-7650 2150);
PAINT GREEN (-7650 2150);
DISPLAY INVISIBLE (-7650 2150);
FORCEPROP 1 LAST PART_NUMBER TP33
J 0
(-7800 2300);
DISPLAY 0.723404 (-7800 2300);
PAINT GREEN (-7800 2300);
DISPLAY INVISIBLE (-7800 2300);
FORCEADD PICOPROBE_BXA..1
R 4
(-5750 2200);
FORCEPROP 1 LAST LOCATION J74
R 2
J 0
(-5600 2000);
DISPLAY 0.723404 (-5600 2000);
PAINT GREEN (-5600 2000);
FORCEPROP 2 LAST SEC 1
J 0
(-5450 2325);
DISPLAY 0.680851 (-5450 2325);
PAINT MONO (-5450 2325);
DISPLAY INVISIBLE (-5450 2325);
FORCEPROP 2 LASTPIN (-6050 2200) $PN 1
J 2
(-6060 2210);
DISPLAY 0.680851 (-6060 2210);
PAINT MONO (-6060 2210);
FORCEPROP 2 LASTPIN (-6050 2150) $PN 2
J 2
(-6060 2160);
DISPLAY 0.680851 (-6060 2160);
PAINT MONO (-6060 2160);
FORCEPROP 2 LASTPIN (-5450 2150) $PN 3
J 0
(-5440 2160);
DISPLAY 0.680851 (-5440 2160);
PAINT MONO (-5440 2160);
FORCEPROP 2 LAST VALUE DELTA-L 4.0
R 2
J 0
(-5550 2375);
DISPLAY 0.680851 (-5550 2375);
FORCEPROP 2 LAST PART_TYPE SMLF
R 2
J 0
(-5550 2350);
DISPLAY 0.680851 (-5550 2350);
FORCEPROP 1 LAST MATERIAL EMPTY
R 2
J 0
(-5596 2095);
DISPLAY 0.723404 (-5596 2095);
PAINT GREEN (-5596 2095);
FORCEPROP 1 LAST CDS_LMAN_SYM_OUTLINE -150,100,150,-100
R 2
J 0
(-5750 2200);
DISPLAY 0.468085 (-5750 2200);
PAINT GREEN (-5750 2200);
DISPLAY INVISIBLE (-5750 2200);
FORCEPROP 2 LAST CDS_LIB pure_quanta
J 0
(-5750 2200);
DISPLAY INVISIBLE (-5750 2200);
FORCEPROP 2 LAST SEC_TYPE 
J 0
(-5450 2325);
DISPLAY 0.680851 (-5450 2325);
DISPLAY INVISIBLE (-5450 2325);
FORCEPROP 1 LAST NEEDS_NO_SIZE TRUE
R 2
J 0
(-5750 2200);
DISPLAY 0.723404 (-5750 2200);
PAINT GREEN (-5750 2200);
DISPLAY INVISIBLE (-5750 2200);
FORCEPROP 1 LAST PATH I76
R 2
J 0
(-5750 2200);
DISPLAY 0.723404 (-5750 2200);
PAINT GREEN (-5750 2200);
DISPLAY INVISIBLE (-5750 2200);
FORCEPROP 1 LAST PART_NUMBER TP33
R 2
J 0
(-5600 2050);
DISPLAY 0.723404 (-5600 2050);
PAINT GREEN (-5600 2050);
DISPLAY INVISIBLE (-5600 2050);
FORCEADD PICOPROBE_BXA..1
(-7675 1450);
FORCEPROP 1 LAST LOCATION J114
J 0
(-7825 1750);
DISPLAY 0.723404 (-7825 1750);
PAINT GREEN (-7825 1750);
FORCEPROP 2 LAST SEC 1
J 0
(-7825 1800);
DISPLAY 0.680851 (-7825 1800);
PAINT MONO (-7825 1800);
DISPLAY INVISIBLE (-7825 1800);
FORCEPROP 2 LASTPIN (-7375 1450) $PN 1
J 0
(-7365 1460);
DISPLAY 0.680851 (-7365 1460);
PAINT MONO (-7365 1460);
FORCEPROP 2 LASTPIN (-7375 1500) $PN 2
J 0
(-7365 1510);
DISPLAY 0.680851 (-7365 1510);
PAINT MONO (-7365 1510);
FORCEPROP 2 LASTPIN (-7975 1500) $PN 3
J 2
(-7985 1510);
DISPLAY 0.680851 (-7985 1510);
PAINT MONO (-7985 1510);
FORCEPROP 1 LAST MATERIAL EMPTY
J 0
(-7829 1555);
DISPLAY 0.723404 (-7829 1555);
PAINT GREEN (-7829 1555);
FORCEPROP 2 LAST VALUE DELTA-L 4.0
J 0
(-7825 1650);
DISPLAY 0.680851 (-7825 1650);
FORCEPROP 2 LAST PART_TYPE SMLF
J 0
(-7825 1700);
DISPLAY 0.680851 (-7825 1700);
FORCEPROP 1 LAST NEEDS_NO_SIZE TRUE
J 0
(-7675 1450);
DISPLAY 0.723404 (-7675 1450);
PAINT GREEN (-7675 1450);
DISPLAY INVISIBLE (-7675 1450);
FORCEPROP 2 LAST SEC_TYPE 
J 0
(-7825 1800);
DISPLAY 0.680851 (-7825 1800);
DISPLAY INVISIBLE (-7825 1800);
FORCEPROP 1 LAST CDS_LMAN_SYM_OUTLINE -150,100,150,-100
J 0
(-7675 1450);
DISPLAY 0.468085 (-7675 1450);
PAINT GREEN (-7675 1450);
DISPLAY INVISIBLE (-7675 1450);
FORCEPROP 2 LAST CDS_LIB pure_quanta
J 0
(-7675 1450);
DISPLAY INVISIBLE (-7675 1450);
FORCEPROP 1 LAST PATH I77
J 0
(-7675 1450);
DISPLAY 0.723404 (-7675 1450);
PAINT GREEN (-7675 1450);
DISPLAY INVISIBLE (-7675 1450);
FORCEPROP 1 LAST PART_NUMBER TP33
J 0
(-7825 1600);
DISPLAY 0.723404 (-7825 1600);
PAINT GREEN (-7825 1600);
DISPLAY INVISIBLE (-7825 1600);
FORCEADD PICOPROBE_BXA..1
R 4
(-5750 1500);
FORCEPROP 1 LAST LOCATION J116
R 2
J 0
(-5600 1300);
DISPLAY 0.723404 (-5600 1300);
PAINT GREEN (-5600 1300);
FORCEPROP 2 LAST SEC 1
J 0
(-5450 1625);
DISPLAY 0.680851 (-5450 1625);
PAINT MONO (-5450 1625);
DISPLAY INVISIBLE (-5450 1625);
FORCEPROP 2 LASTPIN (-6050 1500) $PN 1
J 2
(-6060 1510);
DISPLAY 0.680851 (-6060 1510);
PAINT MONO (-6060 1510);
FORCEPROP 2 LASTPIN (-6050 1450) $PN 2
J 2
(-6060 1460);
DISPLAY 0.680851 (-6060 1460);
PAINT MONO (-6060 1460);
FORCEPROP 2 LASTPIN (-5450 1450) $PN 3
J 0
(-5440 1460);
DISPLAY 0.680851 (-5440 1460);
PAINT MONO (-5440 1460);
FORCEPROP 2 LAST VALUE DELTA-L 4.0
R 2
J 0
(-5550 1675);
DISPLAY 0.680851 (-5550 1675);
FORCEPROP 2 LAST PART_TYPE SMLF
R 2
J 0
(-5550 1650);
DISPLAY 0.680851 (-5550 1650);
FORCEPROP 1 LAST MATERIAL EMPTY
R 2
J 0
(-5596 1395);
DISPLAY 0.723404 (-5596 1395);
PAINT GREEN (-5596 1395);
FORCEPROP 1 LAST NEEDS_NO_SIZE TRUE
R 2
J 0
(-5750 1500);
DISPLAY 0.723404 (-5750 1500);
PAINT GREEN (-5750 1500);
DISPLAY INVISIBLE (-5750 1500);
FORCEPROP 2 LAST SEC_TYPE 
J 0
(-5450 1625);
DISPLAY 0.680851 (-5450 1625);
DISPLAY INVISIBLE (-5450 1625);
FORCEPROP 1 LAST CDS_LMAN_SYM_OUTLINE -150,100,150,-100
R 2
J 0
(-5750 1500);
DISPLAY 0.468085 (-5750 1500);
PAINT GREEN (-5750 1500);
DISPLAY INVISIBLE (-5750 1500);
FORCEPROP 2 LAST CDS_LIB pure_quanta
J 0
(-5750 1500);
DISPLAY INVISIBLE (-5750 1500);
FORCEPROP 1 LAST PATH I78
R 2
J 0
(-5750 1500);
DISPLAY 0.723404 (-5750 1500);
PAINT GREEN (-5750 1500);
DISPLAY INVISIBLE (-5750 1500);
FORCEPROP 1 LAST PART_NUMBER TP33
R 2
J 0
(-5600 1350);
DISPLAY 0.723404 (-5600 1350);
PAINT GREEN (-5600 1350);
DISPLAY INVISIBLE (-5600 1350);
FORCEADD PICOPROBE_BXA..1
(-7725 750);
FORCEPROP 1 LAST LOCATION J115
J 0
(-7875 1050);
DISPLAY 0.723404 (-7875 1050);
PAINT GREEN (-7875 1050);
FORCEPROP 2 LAST SEC 1
J 0
(-7875 1100);
DISPLAY 0.680851 (-7875 1100);
PAINT MONO (-7875 1100);
DISPLAY INVISIBLE (-7875 1100);
FORCEPROP 2 LASTPIN (-7425 750) $PN 1
J 0
(-7415 760);
DISPLAY 0.680851 (-7415 760);
PAINT MONO (-7415 760);
FORCEPROP 2 LASTPIN (-7425 800) $PN 2
J 0
(-7415 810);
DISPLAY 0.680851 (-7415 810);
PAINT MONO (-7415 810);
FORCEPROP 2 LASTPIN (-8025 800) $PN 3
J 2
(-8035 810);
DISPLAY 0.680851 (-8035 810);
PAINT MONO (-8035 810);
FORCEPROP 2 LAST VALUE DELTA-L 4.0
J 0
(-7875 950);
DISPLAY 0.680851 (-7875 950);
FORCEPROP 2 LAST PART_TYPE SMLF
J 0
(-7875 1000);
DISPLAY 0.680851 (-7875 1000);
FORCEPROP 1 LAST MATERIAL EMPTY
J 0
(-7879 855);
DISPLAY 0.723404 (-7879 855);
PAINT GREEN (-7879 855);
FORCEPROP 2 LAST SEC_TYPE 
J 0
(-7875 1100);
DISPLAY 0.680851 (-7875 1100);
DISPLAY INVISIBLE (-7875 1100);
FORCEPROP 2 LAST CDS_LIB pure_quanta
J 0
(-7725 750);
DISPLAY INVISIBLE (-7725 750);
FORCEPROP 1 LAST CDS_LMAN_SYM_OUTLINE -150,100,150,-100
J 0
(-7725 750);
DISPLAY 0.468085 (-7725 750);
PAINT GREEN (-7725 750);
DISPLAY INVISIBLE (-7725 750);
FORCEPROP 1 LAST NEEDS_NO_SIZE TRUE
J 0
(-7725 750);
DISPLAY 0.723404 (-7725 750);
PAINT GREEN (-7725 750);
DISPLAY INVISIBLE (-7725 750);
FORCEPROP 1 LAST PATH I79
J 0
(-7725 750);
DISPLAY 0.723404 (-7725 750);
PAINT GREEN (-7725 750);
DISPLAY INVISIBLE (-7725 750);
FORCEPROP 1 LAST PART_NUMBER TP33
J 0
(-7875 900);
DISPLAY 0.723404 (-7875 900);
PAINT GREEN (-7875 900);
DISPLAY INVISIBLE (-7875 900);
FORCEADD UNIVERSAL_GND..1
(-8075 575);
FORCEPROP 3 LASTPIN (-8075 625) SIG_NAME DELTA_L_GND_1\g
J 0
(-8065 635);
DISPLAY 0.659574 (-8065 635);
PAINT MONO (-8065 635);
DISPLAY INVISIBLE (-8065 635);
FORCEPROP 1 LAST HDL_POWER DELTA_L_GND_1
J 1
(-8050 500);
DISPLAY 0.872340 (-8050 500);
PAINT GREEN (-8050 500);
FORCEPROP 2 LAST CDS_LIB pure_quanta_power
J 0
(-8075 575);
DISPLAY INVISIBLE (-8075 575);
FORCEPROP 1 LAST PATH I8
J 0
(-8000 575);
DISPLAY 0.872340 (-8000 575);
PAINT AQUA (-8000 575);
DISPLAY INVISIBLE (-8000 575);
FORCEADD PICOPROBE_BXA..1
R 4
(-5725 800);
FORCEPROP 1 LAST LOCATION J117
R 2
J 0
(-5550 600);
DISPLAY 0.723404 (-5550 600);
PAINT GREEN (-5550 600);
FORCEPROP 2 LAST SEC 1
J 0
(-5425 925);
DISPLAY 0.680851 (-5425 925);
PAINT MONO (-5425 925);
DISPLAY INVISIBLE (-5425 925);
FORCEPROP 2 LASTPIN (-6025 800) $PN 1
J 2
(-6035 810);
DISPLAY 0.680851 (-6035 810);
PAINT MONO (-6035 810);
FORCEPROP 2 LASTPIN (-6025 750) $PN 2
J 2
(-6035 760);
DISPLAY 0.680851 (-6035 760);
PAINT MONO (-6035 760);
FORCEPROP 2 LASTPIN (-5425 750) $PN 3
J 0
(-5415 760);
DISPLAY 0.680851 (-5415 760);
PAINT MONO (-5415 760);
FORCEPROP 2 LAST PART_TYPE SMLF
R 2
J 0
(-5525 950);
DISPLAY 0.680851 (-5525 950);
FORCEPROP 1 LAST MATERIAL EMPTY
R 2
J 0
(-5571 695);
DISPLAY 0.723404 (-5571 695);
PAINT GREEN (-5571 695);
FORCEPROP 2 LAST VALUE DELTA-L 4.0
R 2
J 0
(-5525 975);
DISPLAY 0.680851 (-5525 975);
FORCEPROP 2 LAST SEC_TYPE 
J 0
(-5425 925);
DISPLAY 0.680851 (-5425 925);
DISPLAY INVISIBLE (-5425 925);
FORCEPROP 2 LAST CDS_LIB pure_quanta
J 0
(-5725 800);
DISPLAY INVISIBLE (-5725 800);
FORCEPROP 1 LAST CDS_LMAN_SYM_OUTLINE -150,100,150,-100
R 2
J 0
(-5725 800);
DISPLAY 0.468085 (-5725 800);
PAINT GREEN (-5725 800);
DISPLAY INVISIBLE (-5725 800);
FORCEPROP 1 LAST NEEDS_NO_SIZE TRUE
R 2
J 0
(-5725 800);
DISPLAY 0.723404 (-5725 800);
PAINT GREEN (-5725 800);
DISPLAY INVISIBLE (-5725 800);
FORCEPROP 1 LAST PATH I80
R 2
J 0
(-5725 800);
DISPLAY 0.723404 (-5725 800);
PAINT GREEN (-5725 800);
DISPLAY INVISIBLE (-5725 800);
FORCEPROP 1 LAST PART_NUMBER TP33
R 2
J 0
(-5575 650);
DISPLAY 0.723404 (-5575 650);
PAINT GREEN (-5575 650);
DISPLAY INVISIBLE (-5575 650);
FORCEADD PICOPROBE_BXA..1
(-3525 5800);
FORCEPROP 1 LAST LOCATION J75
J 0
(-3675 6100);
DISPLAY 0.723404 (-3675 6100);
PAINT GREEN (-3675 6100);
FORCEPROP 2 LAST SEC 1
J 0
(-3675 6150);
DISPLAY 0.680851 (-3675 6150);
PAINT MONO (-3675 6150);
DISPLAY INVISIBLE (-3675 6150);
FORCEPROP 2 LASTPIN (-3225 5800) $PN 1
J 0
(-3215 5810);
DISPLAY 0.680851 (-3215 5810);
PAINT MONO (-3215 5810);
FORCEPROP 2 LASTPIN (-3225 5850) $PN 2
J 0
(-3215 5860);
DISPLAY 0.680851 (-3215 5860);
PAINT MONO (-3215 5860);
FORCEPROP 2 LASTPIN (-3825 5850) $PN 3
J 2
(-3835 5860);
DISPLAY 0.680851 (-3835 5860);
PAINT MONO (-3835 5860);
FORCEPROP 2 LAST PART_TYPE SMLF
J 0
(-3675 6050);
DISPLAY 0.680851 (-3675 6050);
FORCEPROP 2 LAST VALUE DELTA-L 4.0
J 0
(-3675 6000);
DISPLAY 0.680851 (-3675 6000);
FORCEPROP 1 LAST MATERIAL EMPTY
J 0
(-3679 5905);
DISPLAY 0.723404 (-3679 5905);
PAINT GREEN (-3679 5905);
FORCEPROP 2 LAST CDS_LIB pure_quanta
J 0
(-3525 5800);
DISPLAY INVISIBLE (-3525 5800);
FORCEPROP 1 LAST CDS_LMAN_SYM_OUTLINE -150,100,150,-100
J 0
(-3525 5800);
DISPLAY 0.468085 (-3525 5800);
PAINT GREEN (-3525 5800);
DISPLAY INVISIBLE (-3525 5800);
FORCEPROP 2 LAST SEC_TYPE 
J 0
(-3675 6150);
DISPLAY 0.680851 (-3675 6150);
DISPLAY INVISIBLE (-3675 6150);
FORCEPROP 1 LAST NEEDS_NO_SIZE TRUE
J 0
(-3525 5800);
DISPLAY 0.723404 (-3525 5800);
PAINT GREEN (-3525 5800);
DISPLAY INVISIBLE (-3525 5800);
FORCEPROP 1 LAST PATH I81
J 0
(-3525 5800);
DISPLAY 0.723404 (-3525 5800);
PAINT GREEN (-3525 5800);
DISPLAY INVISIBLE (-3525 5800);
FORCEPROP 1 LAST PART_NUMBER TP33
J 0
(-3675 5950);
DISPLAY 0.723404 (-3675 5950);
PAINT GREEN (-3675 5950);
DISPLAY INVISIBLE (-3675 5950);
FORCEADD PICOPROBE_BXA..1
R 4
(-1625 5850);
FORCEPROP 1 LAST LOCATION J81
R 2
J 0
(-1475 5650);
DISPLAY 0.723404 (-1475 5650);
PAINT GREEN (-1475 5650);
FORCEPROP 2 LAST SEC 1
J 0
(-1325 5975);
DISPLAY 0.680851 (-1325 5975);
PAINT MONO (-1325 5975);
DISPLAY INVISIBLE (-1325 5975);
FORCEPROP 2 LASTPIN (-1925 5850) $PN 1
J 2
(-1935 5860);
DISPLAY 0.680851 (-1935 5860);
PAINT MONO (-1935 5860);
FORCEPROP 2 LASTPIN (-1925 5800) $PN 2
J 2
(-1935 5810);
DISPLAY 0.680851 (-1935 5810);
PAINT MONO (-1935 5810);
FORCEPROP 2 LASTPIN (-1325 5800) $PN 3
J 0
(-1315 5810);
DISPLAY 0.680851 (-1315 5810);
PAINT MONO (-1315 5810);
FORCEPROP 1 LAST MATERIAL EMPTY
R 2
J 0
(-1471 5745);
DISPLAY 0.723404 (-1471 5745);
PAINT GREEN (-1471 5745);
FORCEPROP 2 LAST VALUE DELTA-L 4.0
R 2
J 0
(-1425 6025);
DISPLAY 0.680851 (-1425 6025);
FORCEPROP 2 LAST PART_TYPE SMLF
R 2
J 0
(-1425 6000);
DISPLAY 0.680851 (-1425 6000);
FORCEPROP 2 LAST CDS_LIB pure_quanta
J 0
(-1625 5850);
DISPLAY INVISIBLE (-1625 5850);
FORCEPROP 1 LAST CDS_LMAN_SYM_OUTLINE -150,100,150,-100
R 2
J 0
(-1625 5850);
DISPLAY 0.468085 (-1625 5850);
PAINT GREEN (-1625 5850);
DISPLAY INVISIBLE (-1625 5850);
FORCEPROP 2 LAST SEC_TYPE 
J 0
(-1325 5975);
DISPLAY 0.680851 (-1325 5975);
DISPLAY INVISIBLE (-1325 5975);
FORCEPROP 1 LAST NEEDS_NO_SIZE TRUE
R 2
J 0
(-1625 5850);
DISPLAY 0.723404 (-1625 5850);
PAINT GREEN (-1625 5850);
DISPLAY INVISIBLE (-1625 5850);
FORCEPROP 1 LAST PATH I82
R 2
J 0
(-1625 5850);
DISPLAY 0.723404 (-1625 5850);
PAINT GREEN (-1625 5850);
DISPLAY INVISIBLE (-1625 5850);
FORCEPROP 1 LAST PART_NUMBER TP33
R 2
J 0
(-1475 5700);
DISPLAY 0.723404 (-1475 5700);
PAINT GREEN (-1475 5700);
DISPLAY INVISIBLE (-1475 5700);
FORCEADD PICOPROBE_BXA..1
(-3575 5050);
FORCEPROP 1 LAST LOCATION J76
J 0
(-3725 5350);
DISPLAY 0.723404 (-3725 5350);
PAINT GREEN (-3725 5350);
FORCEPROP 2 LAST SEC 1
J 0
(-3725 5400);
DISPLAY 0.680851 (-3725 5400);
PAINT MONO (-3725 5400);
DISPLAY INVISIBLE (-3725 5400);
FORCEPROP 2 LASTPIN (-3275 5050) $PN 1
J 0
(-3265 5060);
DISPLAY 0.680851 (-3265 5060);
PAINT MONO (-3265 5060);
FORCEPROP 2 LASTPIN (-3275 5100) $PN 2
J 0
(-3265 5110);
DISPLAY 0.680851 (-3265 5110);
PAINT MONO (-3265 5110);
FORCEPROP 2 LASTPIN (-3875 5100) $PN 3
J 2
(-3885 5110);
DISPLAY 0.680851 (-3885 5110);
PAINT MONO (-3885 5110);
FORCEPROP 2 LAST PART_TYPE SMLF
J 0
(-3725 5300);
DISPLAY 0.680851 (-3725 5300);
FORCEPROP 2 LAST VALUE DELTA-L 4.0
J 0
(-3725 5250);
DISPLAY 0.680851 (-3725 5250);
FORCEPROP 1 LAST MATERIAL EMPTY
J 0
(-3729 5155);
DISPLAY 0.723404 (-3729 5155);
PAINT GREEN (-3729 5155);
FORCEPROP 1 LAST NEEDS_NO_SIZE TRUE
J 0
(-3575 5050);
DISPLAY 0.723404 (-3575 5050);
PAINT GREEN (-3575 5050);
DISPLAY INVISIBLE (-3575 5050);
FORCEPROP 2 LAST SEC_TYPE 
J 0
(-3725 5400);
DISPLAY 0.680851 (-3725 5400);
DISPLAY INVISIBLE (-3725 5400);
FORCEPROP 1 LAST CDS_LMAN_SYM_OUTLINE -150,100,150,-100
J 0
(-3575 5050);
DISPLAY 0.468085 (-3575 5050);
PAINT GREEN (-3575 5050);
DISPLAY INVISIBLE (-3575 5050);
FORCEPROP 2 LAST CDS_LIB pure_quanta
J 0
(-3575 5050);
DISPLAY INVISIBLE (-3575 5050);
FORCEPROP 1 LAST PATH I83
J 0
(-3575 5050);
DISPLAY 0.723404 (-3575 5050);
PAINT GREEN (-3575 5050);
DISPLAY INVISIBLE (-3575 5050);
FORCEPROP 1 LAST PART_NUMBER TP33
J 0
(-3725 5200);
DISPLAY 0.723404 (-3725 5200);
PAINT GREEN (-3725 5200);
DISPLAY INVISIBLE (-3725 5200);
FORCEADD PICOPROBE_BXA..1
R 4
(-1625 5100);
FORCEPROP 1 LAST LOCATION J82
R 2
J 0
(-1475 4900);
DISPLAY 0.723404 (-1475 4900);
PAINT GREEN (-1475 4900);
FORCEPROP 2 LAST SEC 1
J 0
(-1325 5225);
DISPLAY 0.680851 (-1325 5225);
PAINT MONO (-1325 5225);
DISPLAY INVISIBLE (-1325 5225);
FORCEPROP 2 LASTPIN (-1925 5100) $PN 1
J 2
(-1935 5110);
DISPLAY 0.680851 (-1935 5110);
PAINT MONO (-1935 5110);
FORCEPROP 2 LASTPIN (-1925 5050) $PN 2
J 2
(-1935 5060);
DISPLAY 0.680851 (-1935 5060);
PAINT MONO (-1935 5060);
FORCEPROP 2 LASTPIN (-1325 5050) $PN 3
J 0
(-1315 5060);
DISPLAY 0.680851 (-1315 5060);
PAINT MONO (-1315 5060);
FORCEPROP 1 LAST MATERIAL EMPTY
R 2
J 0
(-1471 4995);
DISPLAY 0.723404 (-1471 4995);
PAINT GREEN (-1471 4995);
FORCEPROP 2 LAST VALUE DELTA-L 4.0
R 2
J 0
(-1425 5275);
DISPLAY 0.680851 (-1425 5275);
FORCEPROP 2 LAST PART_TYPE SMLF
R 2
J 0
(-1425 5250);
DISPLAY 0.680851 (-1425 5250);
FORCEPROP 1 LAST NEEDS_NO_SIZE TRUE
R 2
J 0
(-1625 5100);
DISPLAY 0.723404 (-1625 5100);
PAINT GREEN (-1625 5100);
DISPLAY INVISIBLE (-1625 5100);
FORCEPROP 2 LAST SEC_TYPE 
J 0
(-1325 5225);
DISPLAY 0.680851 (-1325 5225);
DISPLAY INVISIBLE (-1325 5225);
FORCEPROP 1 LAST CDS_LMAN_SYM_OUTLINE -150,100,150,-100
R 2
J 0
(-1625 5100);
DISPLAY 0.468085 (-1625 5100);
PAINT GREEN (-1625 5100);
DISPLAY INVISIBLE (-1625 5100);
FORCEPROP 2 LAST CDS_LIB pure_quanta
J 0
(-1625 5100);
DISPLAY INVISIBLE (-1625 5100);
FORCEPROP 1 LAST PATH I84
R 2
J 0
(-1625 5100);
DISPLAY 0.723404 (-1625 5100);
PAINT GREEN (-1625 5100);
DISPLAY INVISIBLE (-1625 5100);
FORCEPROP 1 LAST PART_NUMBER TP33
R 2
J 0
(-1475 4950);
DISPLAY 0.723404 (-1475 4950);
PAINT GREEN (-1475 4950);
DISPLAY INVISIBLE (-1475 4950);
FORCEADD PICOPROBE_BXA..1
(-3525 4325);
FORCEPROP 1 LAST LOCATION J77
J 0
(-3675 4625);
DISPLAY 0.723404 (-3675 4625);
PAINT GREEN (-3675 4625);
FORCEPROP 2 LAST SEC 1
J 0
(-3675 4675);
DISPLAY 0.680851 (-3675 4675);
PAINT MONO (-3675 4675);
DISPLAY INVISIBLE (-3675 4675);
FORCEPROP 2 LASTPIN (-3225 4325) $PN 1
J 0
(-3215 4335);
DISPLAY 0.680851 (-3215 4335);
PAINT MONO (-3215 4335);
FORCEPROP 2 LASTPIN (-3225 4375) $PN 2
J 0
(-3215 4385);
DISPLAY 0.680851 (-3215 4385);
PAINT MONO (-3215 4385);
FORCEPROP 2 LASTPIN (-3825 4375) $PN 3
J 2
(-3835 4385);
DISPLAY 0.680851 (-3835 4385);
PAINT MONO (-3835 4385);
FORCEPROP 2 LAST PART_TYPE SMLF
J 0
(-3675 4575);
DISPLAY 0.680851 (-3675 4575);
FORCEPROP 2 LAST VALUE DELTA-L 4.0
J 0
(-3675 4525);
DISPLAY 0.680851 (-3675 4525);
FORCEPROP 1 LAST MATERIAL EMPTY
J 0
(-3679 4430);
DISPLAY 0.723404 (-3679 4430);
PAINT GREEN (-3679 4430);
FORCEPROP 2 LAST CDS_LIB pure_quanta
J 0
(-3525 4325);
DISPLAY INVISIBLE (-3525 4325);
FORCEPROP 1 LAST CDS_LMAN_SYM_OUTLINE -150,100,150,-100
J 0
(-3525 4325);
DISPLAY 0.468085 (-3525 4325);
PAINT GREEN (-3525 4325);
DISPLAY INVISIBLE (-3525 4325);
FORCEPROP 2 LAST SEC_TYPE 
J 0
(-3675 4675);
DISPLAY 0.680851 (-3675 4675);
DISPLAY INVISIBLE (-3675 4675);
FORCEPROP 1 LAST NEEDS_NO_SIZE TRUE
J 0
(-3525 4325);
DISPLAY 0.723404 (-3525 4325);
PAINT GREEN (-3525 4325);
DISPLAY INVISIBLE (-3525 4325);
FORCEPROP 1 LAST PATH I85
J 0
(-3525 4325);
DISPLAY 0.723404 (-3525 4325);
PAINT GREEN (-3525 4325);
DISPLAY INVISIBLE (-3525 4325);
FORCEPROP 1 LAST PART_NUMBER TP33
J 0
(-3675 4475);
DISPLAY 0.723404 (-3675 4475);
PAINT GREEN (-3675 4475);
DISPLAY INVISIBLE (-3675 4475);
FORCEADD PICOPROBE_BXA..1
R 4
(-1675 4375);
FORCEPROP 1 LAST LOCATION J83
R 2
J 0
(-1525 4150);
DISPLAY 0.723404 (-1525 4150);
PAINT GREEN (-1525 4150);
FORCEPROP 2 LAST SEC 1
J 0
(-1375 4500);
DISPLAY 0.680851 (-1375 4500);
PAINT MONO (-1375 4500);
DISPLAY INVISIBLE (-1375 4500);
FORCEPROP 2 LASTPIN (-1975 4375) $PN 1
J 2
(-1985 4385);
DISPLAY 0.680851 (-1985 4385);
PAINT MONO (-1985 4385);
FORCEPROP 2 LASTPIN (-1975 4325) $PN 2
J 2
(-1985 4335);
DISPLAY 0.680851 (-1985 4335);
PAINT MONO (-1985 4335);
FORCEPROP 2 LASTPIN (-1375 4325) $PN 3
J 0
(-1365 4335);
DISPLAY 0.680851 (-1365 4335);
PAINT MONO (-1365 4335);
FORCEPROP 1 LAST MATERIAL EMPTY
R 2
J 0
(-1521 4270);
DISPLAY 0.723404 (-1521 4270);
PAINT GREEN (-1521 4270);
FORCEPROP 2 LAST VALUE DELTA-L 4.0
R 2
J 0
(-1475 4550);
DISPLAY 0.680851 (-1475 4550);
FORCEPROP 2 LAST PART_TYPE SMLF
R 2
J 0
(-1475 4525);
DISPLAY 0.680851 (-1475 4525);
FORCEPROP 2 LAST CDS_LIB pure_quanta
J 0
(-1675 4375);
DISPLAY INVISIBLE (-1675 4375);
FORCEPROP 1 LAST CDS_LMAN_SYM_OUTLINE -150,100,150,-100
R 2
J 0
(-1675 4375);
DISPLAY 0.468085 (-1675 4375);
PAINT GREEN (-1675 4375);
DISPLAY INVISIBLE (-1675 4375);
FORCEPROP 2 LAST SEC_TYPE 
J 0
(-1375 4500);
DISPLAY 0.680851 (-1375 4500);
DISPLAY INVISIBLE (-1375 4500);
FORCEPROP 1 LAST NEEDS_NO_SIZE TRUE
R 2
J 0
(-1675 4375);
DISPLAY 0.723404 (-1675 4375);
PAINT GREEN (-1675 4375);
DISPLAY INVISIBLE (-1675 4375);
FORCEPROP 1 LAST PATH I86
R 2
J 0
(-1675 4375);
DISPLAY 0.723404 (-1675 4375);
PAINT GREEN (-1675 4375);
DISPLAY INVISIBLE (-1675 4375);
FORCEPROP 1 LAST PART_NUMBER TP33
R 2
J 0
(-1525 4225);
DISPLAY 0.723404 (-1525 4225);
PAINT GREEN (-1525 4225);
DISPLAY INVISIBLE (-1525 4225);
FORCEADD PICOPROBE_BXA..1
(-3550 3575);
FORCEPROP 1 LAST LOCATION J78
J 0
(-3700 3875);
DISPLAY 0.723404 (-3700 3875);
PAINT GREEN (-3700 3875);
FORCEPROP 2 LAST SEC 1
J 0
(-3700 3925);
DISPLAY 0.680851 (-3700 3925);
PAINT MONO (-3700 3925);
DISPLAY INVISIBLE (-3700 3925);
FORCEPROP 2 LASTPIN (-3250 3575) $PN 1
J 0
(-3240 3585);
DISPLAY 0.680851 (-3240 3585);
PAINT MONO (-3240 3585);
FORCEPROP 2 LASTPIN (-3250 3625) $PN 2
J 0
(-3240 3635);
DISPLAY 0.680851 (-3240 3635);
PAINT MONO (-3240 3635);
FORCEPROP 2 LASTPIN (-3850 3625) $PN 3
J 2
(-3860 3635);
DISPLAY 0.680851 (-3860 3635);
PAINT MONO (-3860 3635);
FORCEPROP 2 LAST VALUE DELTA-L 4.0
J 0
(-3700 3775);
DISPLAY 0.680851 (-3700 3775);
FORCEPROP 1 LAST MATERIAL EMPTY
J 0
(-3704 3680);
DISPLAY 0.723404 (-3704 3680);
PAINT GREEN (-3704 3680);
FORCEPROP 2 LAST PART_TYPE SMLF
J 0
(-3700 3825);
DISPLAY 0.680851 (-3700 3825);
FORCEPROP 1 LAST NEEDS_NO_SIZE TRUE
J 0
(-3550 3575);
DISPLAY 0.723404 (-3550 3575);
PAINT GREEN (-3550 3575);
DISPLAY INVISIBLE (-3550 3575);
FORCEPROP 2 LAST SEC_TYPE 
J 0
(-3700 3925);
DISPLAY 0.680851 (-3700 3925);
DISPLAY INVISIBLE (-3700 3925);
FORCEPROP 1 LAST CDS_LMAN_SYM_OUTLINE -150,100,150,-100
J 0
(-3550 3575);
DISPLAY 0.468085 (-3550 3575);
PAINT GREEN (-3550 3575);
DISPLAY INVISIBLE (-3550 3575);
FORCEPROP 2 LAST CDS_LIB pure_quanta
J 0
(-3550 3575);
DISPLAY INVISIBLE (-3550 3575);
FORCEPROP 1 LAST PATH I87
J 0
(-3550 3575);
DISPLAY 0.723404 (-3550 3575);
PAINT GREEN (-3550 3575);
DISPLAY INVISIBLE (-3550 3575);
FORCEPROP 1 LAST PART_NUMBER TP33
J 0
(-3700 3725);
DISPLAY 0.723404 (-3700 3725);
PAINT GREEN (-3700 3725);
DISPLAY INVISIBLE (-3700 3725);
FORCEADD PICOPROBE_BXA..1
R 4
(-1600 3625);
FORCEPROP 1 LAST LOCATION J84
R 2
J 0
(-1450 3425);
DISPLAY 0.723404 (-1450 3425);
PAINT GREEN (-1450 3425);
FORCEPROP 2 LAST SEC 1
J 0
(-1300 3750);
DISPLAY 0.680851 (-1300 3750);
PAINT MONO (-1300 3750);
DISPLAY INVISIBLE (-1300 3750);
FORCEPROP 2 LASTPIN (-1900 3625) $PN 1
J 2
(-1910 3635);
DISPLAY 0.680851 (-1910 3635);
PAINT MONO (-1910 3635);
FORCEPROP 2 LASTPIN (-1900 3575) $PN 2
J 2
(-1910 3585);
DISPLAY 0.680851 (-1910 3585);
PAINT MONO (-1910 3585);
FORCEPROP 2 LASTPIN (-1300 3575) $PN 3
J 0
(-1290 3585);
DISPLAY 0.680851 (-1290 3585);
PAINT MONO (-1290 3585);
FORCEPROP 1 LAST MATERIAL EMPTY
R 2
J 0
(-1446 3520);
DISPLAY 0.723404 (-1446 3520);
PAINT GREEN (-1446 3520);
FORCEPROP 2 LAST VALUE DELTA-L 4.0
R 2
J 0
(-1400 3800);
DISPLAY 0.680851 (-1400 3800);
FORCEPROP 2 LAST PART_TYPE SMLF
R 2
J 0
(-1400 3775);
DISPLAY 0.680851 (-1400 3775);
FORCEPROP 1 LAST NEEDS_NO_SIZE TRUE
R 2
J 0
(-1600 3625);
DISPLAY 0.723404 (-1600 3625);
PAINT GREEN (-1600 3625);
DISPLAY INVISIBLE (-1600 3625);
FORCEPROP 2 LAST SEC_TYPE 
J 0
(-1300 3750);
DISPLAY 0.680851 (-1300 3750);
DISPLAY INVISIBLE (-1300 3750);
FORCEPROP 1 LAST CDS_LMAN_SYM_OUTLINE -150,100,150,-100
R 2
J 0
(-1600 3625);
DISPLAY 0.468085 (-1600 3625);
PAINT GREEN (-1600 3625);
DISPLAY INVISIBLE (-1600 3625);
FORCEPROP 2 LAST CDS_LIB pure_quanta
J 0
(-1600 3625);
DISPLAY INVISIBLE (-1600 3625);
FORCEPROP 1 LAST PATH I88
R 2
J 0
(-1600 3625);
DISPLAY 0.723404 (-1600 3625);
PAINT GREEN (-1600 3625);
DISPLAY INVISIBLE (-1600 3625);
FORCEPROP 1 LAST PART_NUMBER TP33
R 2
J 0
(-1450 3475);
DISPLAY 0.723404 (-1450 3475);
PAINT GREEN (-1450 3475);
DISPLAY INVISIBLE (-1450 3475);
FORCEADD PICOPROBE_BXA..1
(-3575 2900);
FORCEPROP 1 LAST LOCATION J79
J 0
(-3725 3200);
DISPLAY 0.723404 (-3725 3200);
PAINT GREEN (-3725 3200);
FORCEPROP 2 LAST SEC 1
J 0
(-3725 3250);
DISPLAY 0.680851 (-3725 3250);
PAINT MONO (-3725 3250);
DISPLAY INVISIBLE (-3725 3250);
FORCEPROP 2 LASTPIN (-3275 2900) $PN 1
J 0
(-3265 2910);
DISPLAY 0.680851 (-3265 2910);
PAINT MONO (-3265 2910);
FORCEPROP 2 LASTPIN (-3275 2950) $PN 2
J 0
(-3265 2960);
DISPLAY 0.680851 (-3265 2960);
PAINT MONO (-3265 2960);
FORCEPROP 2 LASTPIN (-3875 2950) $PN 3
J 2
(-3885 2960);
DISPLAY 0.680851 (-3885 2960);
PAINT MONO (-3885 2960);
FORCEPROP 2 LAST PART_TYPE SMLF
J 0
(-3725 3150);
DISPLAY 0.680851 (-3725 3150);
FORCEPROP 2 LAST VALUE DELTA-L 4.0
J 0
(-3725 3100);
DISPLAY 0.680851 (-3725 3100);
FORCEPROP 1 LAST MATERIAL EMPTY
J 0
(-3729 3005);
DISPLAY 0.723404 (-3729 3005);
PAINT GREEN (-3729 3005);
FORCEPROP 2 LAST CDS_LIB pure_quanta
J 0
(-3575 2900);
DISPLAY INVISIBLE (-3575 2900);
FORCEPROP 1 LAST CDS_LMAN_SYM_OUTLINE -150,100,150,-100
J 0
(-3575 2900);
DISPLAY 0.468085 (-3575 2900);
PAINT GREEN (-3575 2900);
DISPLAY INVISIBLE (-3575 2900);
FORCEPROP 2 LAST SEC_TYPE 
J 0
(-3725 3250);
DISPLAY 0.680851 (-3725 3250);
DISPLAY INVISIBLE (-3725 3250);
FORCEPROP 1 LAST NEEDS_NO_SIZE TRUE
J 0
(-3575 2900);
DISPLAY 0.723404 (-3575 2900);
PAINT GREEN (-3575 2900);
DISPLAY INVISIBLE (-3575 2900);
FORCEPROP 1 LAST PATH I89
J 0
(-3575 2900);
DISPLAY 0.723404 (-3575 2900);
PAINT GREEN (-3575 2900);
DISPLAY INVISIBLE (-3575 2900);
FORCEPROP 1 LAST PART_NUMBER TP33
J 0
(-3725 3050);
DISPLAY 0.723404 (-3725 3050);
PAINT GREEN (-3725 3050);
DISPLAY INVISIBLE (-3725 3050);
FORCEADD PICOPROBE_BXA..1
R 4
(-1625 2950);
FORCEPROP 1 LAST LOCATION J85
R 2
J 0
(-1475 2750);
DISPLAY 0.723404 (-1475 2750);
PAINT GREEN (-1475 2750);
FORCEPROP 2 LAST SEC 1
J 0
(-1325 3075);
DISPLAY 0.680851 (-1325 3075);
PAINT MONO (-1325 3075);
DISPLAY INVISIBLE (-1325 3075);
FORCEPROP 2 LASTPIN (-1925 2950) $PN 1
J 2
(-1935 2960);
DISPLAY 0.680851 (-1935 2960);
PAINT MONO (-1935 2960);
FORCEPROP 2 LASTPIN (-1925 2900) $PN 2
J 2
(-1935 2910);
DISPLAY 0.680851 (-1935 2910);
PAINT MONO (-1935 2910);
FORCEPROP 2 LASTPIN (-1325 2900) $PN 3
J 0
(-1315 2910);
DISPLAY 0.680851 (-1315 2910);
PAINT MONO (-1315 2910);
FORCEPROP 1 LAST MATERIAL EMPTY
R 2
J 0
(-1471 2845);
DISPLAY 0.723404 (-1471 2845);
PAINT GREEN (-1471 2845);
FORCEPROP 2 LAST VALUE DELTA-L 4.0
R 2
J 0
(-1425 3125);
DISPLAY 0.680851 (-1425 3125);
FORCEPROP 2 LAST PART_TYPE SMLF
R 2
J 0
(-1425 3100);
DISPLAY 0.680851 (-1425 3100);
FORCEPROP 2 LAST CDS_LIB pure_quanta
J 0
(-1625 2950);
DISPLAY INVISIBLE (-1625 2950);
FORCEPROP 1 LAST CDS_LMAN_SYM_OUTLINE -150,100,150,-100
R 2
J 0
(-1625 2950);
DISPLAY 0.468085 (-1625 2950);
PAINT GREEN (-1625 2950);
DISPLAY INVISIBLE (-1625 2950);
FORCEPROP 2 LAST SEC_TYPE 
J 0
(-1325 3075);
DISPLAY 0.680851 (-1325 3075);
DISPLAY INVISIBLE (-1325 3075);
FORCEPROP 1 LAST NEEDS_NO_SIZE TRUE
R 2
J 0
(-1625 2950);
DISPLAY 0.723404 (-1625 2950);
PAINT GREEN (-1625 2950);
DISPLAY INVISIBLE (-1625 2950);
FORCEPROP 1 LAST PATH I90
R 2
J 0
(-1625 2950);
DISPLAY 0.723404 (-1625 2950);
PAINT GREEN (-1625 2950);
DISPLAY INVISIBLE (-1625 2950);
FORCEPROP 1 LAST PART_NUMBER TP33
R 2
J 0
(-1475 2800);
DISPLAY 0.723404 (-1475 2800);
PAINT GREEN (-1475 2800);
DISPLAY INVISIBLE (-1475 2800);
FORCEADD PICOPROBE_BXA..1
(-3525 2150);
FORCEPROP 1 LAST LOCATION J80
J 0
(-3675 2450);
DISPLAY 0.723404 (-3675 2450);
PAINT GREEN (-3675 2450);
FORCEPROP 2 LAST SEC 1
J 0
(-3675 2500);
DISPLAY 0.680851 (-3675 2500);
PAINT MONO (-3675 2500);
DISPLAY INVISIBLE (-3675 2500);
FORCEPROP 2 LASTPIN (-3225 2150) $PN 1
J 0
(-3215 2160);
DISPLAY 0.680851 (-3215 2160);
PAINT MONO (-3215 2160);
FORCEPROP 2 LASTPIN (-3225 2200) $PN 2
J 0
(-3215 2210);
DISPLAY 0.680851 (-3215 2210);
PAINT MONO (-3215 2210);
FORCEPROP 2 LASTPIN (-3825 2200) $PN 3
J 2
(-3835 2210);
DISPLAY 0.680851 (-3835 2210);
PAINT MONO (-3835 2210);
FORCEPROP 1 LAST MATERIAL EMPTY
J 0
(-3679 2255);
DISPLAY 0.723404 (-3679 2255);
PAINT GREEN (-3679 2255);
FORCEPROP 2 LAST VALUE DELTA-L 4.0
J 0
(-3675 2350);
DISPLAY 0.680851 (-3675 2350);
FORCEPROP 2 LAST PART_TYPE SMLF
J 0
(-3675 2400);
DISPLAY 0.680851 (-3675 2400);
FORCEPROP 2 LAST CDS_LIB pure_quanta
J 0
(-3525 2150);
DISPLAY INVISIBLE (-3525 2150);
FORCEPROP 1 LAST CDS_LMAN_SYM_OUTLINE -150,100,150,-100
J 0
(-3525 2150);
DISPLAY 0.468085 (-3525 2150);
PAINT GREEN (-3525 2150);
DISPLAY INVISIBLE (-3525 2150);
FORCEPROP 2 LAST SEC_TYPE 
J 0
(-3675 2500);
DISPLAY 0.680851 (-3675 2500);
DISPLAY INVISIBLE (-3675 2500);
FORCEPROP 1 LAST NEEDS_NO_SIZE TRUE
J 0
(-3525 2150);
DISPLAY 0.723404 (-3525 2150);
PAINT GREEN (-3525 2150);
DISPLAY INVISIBLE (-3525 2150);
FORCEPROP 1 LAST PATH I91
J 0
(-3525 2150);
DISPLAY 0.723404 (-3525 2150);
PAINT GREEN (-3525 2150);
DISPLAY INVISIBLE (-3525 2150);
FORCEPROP 1 LAST PART_NUMBER TP33
J 0
(-3675 2300);
DISPLAY 0.723404 (-3675 2300);
PAINT GREEN (-3675 2300);
DISPLAY INVISIBLE (-3675 2300);
FORCEADD PICOPROBE_BXA..1
R 4
(-1600 2200);
FORCEPROP 1 LAST LOCATION J86
R 2
J 0
(-1450 2000);
DISPLAY 0.723404 (-1450 2000);
PAINT GREEN (-1450 2000);
FORCEPROP 2 LAST SEC 1
J 0
(-1300 2325);
DISPLAY 0.680851 (-1300 2325);
PAINT MONO (-1300 2325);
DISPLAY INVISIBLE (-1300 2325);
FORCEPROP 2 LASTPIN (-1900 2200) $PN 1
J 2
(-1910 2210);
DISPLAY 0.680851 (-1910 2210);
PAINT MONO (-1910 2210);
FORCEPROP 2 LASTPIN (-1900 2150) $PN 2
J 2
(-1910 2160);
DISPLAY 0.680851 (-1910 2160);
PAINT MONO (-1910 2160);
FORCEPROP 2 LASTPIN (-1300 2150) $PN 3
J 0
(-1290 2160);
DISPLAY 0.680851 (-1290 2160);
PAINT MONO (-1290 2160);
FORCEPROP 2 LAST PART_TYPE SMLF
R 2
J 0
(-1400 2350);
DISPLAY 0.680851 (-1400 2350);
FORCEPROP 2 LAST VALUE DELTA-L 4.0
R 2
J 0
(-1400 2375);
DISPLAY 0.680851 (-1400 2375);
FORCEPROP 1 LAST MATERIAL EMPTY
R 2
J 0
(-1446 2095);
DISPLAY 0.723404 (-1446 2095);
PAINT GREEN (-1446 2095);
FORCEPROP 2 LAST CDS_LIB pure_quanta
J 0
(-1600 2200);
DISPLAY INVISIBLE (-1600 2200);
FORCEPROP 1 LAST CDS_LMAN_SYM_OUTLINE -150,100,150,-100
R 2
J 0
(-1600 2200);
DISPLAY 0.468085 (-1600 2200);
PAINT GREEN (-1600 2200);
DISPLAY INVISIBLE (-1600 2200);
FORCEPROP 2 LAST SEC_TYPE 
J 0
(-1300 2325);
DISPLAY 0.680851 (-1300 2325);
DISPLAY INVISIBLE (-1300 2325);
FORCEPROP 1 LAST NEEDS_NO_SIZE TRUE
R 2
J 0
(-1600 2200);
DISPLAY 0.723404 (-1600 2200);
PAINT GREEN (-1600 2200);
DISPLAY INVISIBLE (-1600 2200);
FORCEPROP 1 LAST PATH I92
R 2
J 0
(-1600 2200);
DISPLAY 0.723404 (-1600 2200);
PAINT GREEN (-1600 2200);
DISPLAY INVISIBLE (-1600 2200);
FORCEPROP 1 LAST PART_NUMBER TP33
R 2
J 0
(-1450 2050);
DISPLAY 0.723404 (-1450 2050);
PAINT GREEN (-1450 2050);
DISPLAY INVISIBLE (-1450 2050);
FORCEADD PICOPROBE_BXA..1
(-3475 1500);
FORCEPROP 1 LAST LOCATION J118
J 0
(-3625 1800);
DISPLAY 0.723404 (-3625 1800);
PAINT GREEN (-3625 1800);
FORCEPROP 2 LAST SEC 1
J 0
(-3625 1850);
DISPLAY 0.680851 (-3625 1850);
PAINT MONO (-3625 1850);
DISPLAY INVISIBLE (-3625 1850);
FORCEPROP 2 LASTPIN (-3175 1500) $PN 1
J 0
(-3165 1510);
DISPLAY 0.680851 (-3165 1510);
PAINT MONO (-3165 1510);
FORCEPROP 2 LASTPIN (-3175 1550) $PN 2
J 0
(-3165 1560);
DISPLAY 0.680851 (-3165 1560);
PAINT MONO (-3165 1560);
FORCEPROP 2 LASTPIN (-3775 1550) $PN 3
J 2
(-3785 1560);
DISPLAY 0.680851 (-3785 1560);
PAINT MONO (-3785 1560);
FORCEPROP 2 LAST PART_TYPE SMLF
J 0
(-3625 1750);
DISPLAY 0.680851 (-3625 1750);
FORCEPROP 1 LAST MATERIAL EMPTY
J 0
(-3629 1605);
DISPLAY 0.723404 (-3629 1605);
PAINT GREEN (-3629 1605);
FORCEPROP 2 LAST VALUE DELTA-L 4.0
J 0
(-3625 1700);
DISPLAY 0.680851 (-3625 1700);
FORCEPROP 2 LAST CDS_LIB pure_quanta
J 0
(-3475 1500);
DISPLAY INVISIBLE (-3475 1500);
FORCEPROP 1 LAST CDS_LMAN_SYM_OUTLINE -150,100,150,-100
J 0
(-3475 1500);
DISPLAY 0.468085 (-3475 1500);
PAINT GREEN (-3475 1500);
DISPLAY INVISIBLE (-3475 1500);
FORCEPROP 2 LAST SEC_TYPE 
J 0
(-3625 1850);
DISPLAY 0.680851 (-3625 1850);
DISPLAY INVISIBLE (-3625 1850);
FORCEPROP 1 LAST NEEDS_NO_SIZE TRUE
J 0
(-3475 1500);
DISPLAY 0.723404 (-3475 1500);
PAINT GREEN (-3475 1500);
DISPLAY INVISIBLE (-3475 1500);
FORCEPROP 1 LAST PATH I93
J 0
(-3475 1500);
DISPLAY 0.723404 (-3475 1500);
PAINT GREEN (-3475 1500);
DISPLAY INVISIBLE (-3475 1500);
FORCEPROP 1 LAST PART_NUMBER TP33
J 0
(-3625 1650);
DISPLAY 0.723404 (-3625 1650);
PAINT GREEN (-3625 1650);
DISPLAY INVISIBLE (-3625 1650);
FORCEADD PICOPROBE_BXA..1
R 4
(-1575 1550);
FORCEPROP 1 LAST LOCATION J120
R 2
J 0
(-1425 1350);
DISPLAY 0.723404 (-1425 1350);
PAINT GREEN (-1425 1350);
FORCEPROP 2 LAST SEC 1
J 0
(-1275 1675);
DISPLAY 0.680851 (-1275 1675);
PAINT MONO (-1275 1675);
DISPLAY INVISIBLE (-1275 1675);
FORCEPROP 2 LASTPIN (-1875 1550) $PN 1
J 2
(-1885 1560);
DISPLAY 0.680851 (-1885 1560);
PAINT MONO (-1885 1560);
FORCEPROP 2 LASTPIN (-1875 1500) $PN 2
J 2
(-1885 1510);
DISPLAY 0.680851 (-1885 1510);
PAINT MONO (-1885 1510);
FORCEPROP 2 LASTPIN (-1275 1500) $PN 3
J 0
(-1265 1510);
DISPLAY 0.680851 (-1265 1510);
PAINT MONO (-1265 1510);
FORCEPROP 1 LAST MATERIAL EMPTY
R 2
J 0
(-1421 1445);
DISPLAY 0.723404 (-1421 1445);
PAINT GREEN (-1421 1445);
FORCEPROP 2 LAST VALUE DELTA-L 4.0
R 2
J 0
(-1375 1725);
DISPLAY 0.680851 (-1375 1725);
FORCEPROP 2 LAST PART_TYPE SMLF
R 2
J 0
(-1375 1700);
DISPLAY 0.680851 (-1375 1700);
FORCEPROP 2 LAST CDS_LIB pure_quanta
J 0
(-1575 1550);
DISPLAY INVISIBLE (-1575 1550);
FORCEPROP 1 LAST CDS_LMAN_SYM_OUTLINE -150,100,150,-100
R 2
J 0
(-1575 1550);
DISPLAY 0.468085 (-1575 1550);
PAINT GREEN (-1575 1550);
DISPLAY INVISIBLE (-1575 1550);
FORCEPROP 2 LAST SEC_TYPE 
J 0
(-1275 1675);
DISPLAY 0.680851 (-1275 1675);
DISPLAY INVISIBLE (-1275 1675);
FORCEPROP 1 LAST NEEDS_NO_SIZE TRUE
R 2
J 0
(-1575 1550);
DISPLAY 0.723404 (-1575 1550);
PAINT GREEN (-1575 1550);
DISPLAY INVISIBLE (-1575 1550);
FORCEPROP 1 LAST PATH I94
R 2
J 0
(-1575 1550);
DISPLAY 0.723404 (-1575 1550);
PAINT GREEN (-1575 1550);
DISPLAY INVISIBLE (-1575 1550);
FORCEPROP 1 LAST PART_NUMBER TP33
R 2
J 0
(-1425 1400);
DISPLAY 0.723404 (-1425 1400);
PAINT GREEN (-1425 1400);
DISPLAY INVISIBLE (-1425 1400);
FORCEADD PICOPROBE_BXA..1
(-3475 775);
FORCEPROP 1 LAST LOCATION J119
J 0
(-3625 1075);
DISPLAY 0.723404 (-3625 1075);
PAINT GREEN (-3625 1075);
FORCEPROP 2 LAST SEC 1
J 0
(-3625 1125);
DISPLAY 0.680851 (-3625 1125);
PAINT MONO (-3625 1125);
DISPLAY INVISIBLE (-3625 1125);
FORCEPROP 2 LASTPIN (-3175 775) $PN 1
J 0
(-3165 785);
DISPLAY 0.680851 (-3165 785);
PAINT MONO (-3165 785);
FORCEPROP 2 LASTPIN (-3175 825) $PN 2
J 0
(-3165 835);
DISPLAY 0.680851 (-3165 835);
PAINT MONO (-3165 835);
FORCEPROP 2 LASTPIN (-3775 825) $PN 3
J 2
(-3785 835);
DISPLAY 0.680851 (-3785 835);
PAINT MONO (-3785 835);
FORCEPROP 1 LAST MATERIAL EMPTY
J 0
(-3629 880);
DISPLAY 0.723404 (-3629 880);
PAINT GREEN (-3629 880);
FORCEPROP 2 LAST VALUE DELTA-L 4.0
J 0
(-3625 975);
DISPLAY 0.680851 (-3625 975);
FORCEPROP 2 LAST PART_TYPE SMLF
J 0
(-3625 1025);
DISPLAY 0.680851 (-3625 1025);
FORCEPROP 2 LAST SEC_TYPE 
J 0
(-3625 1125);
DISPLAY 0.680851 (-3625 1125);
DISPLAY INVISIBLE (-3625 1125);
FORCEPROP 2 LAST CDS_LIB pure_quanta
J 0
(-3475 775);
DISPLAY INVISIBLE (-3475 775);
FORCEPROP 1 LAST CDS_LMAN_SYM_OUTLINE -150,100,150,-100
J 0
(-3475 775);
DISPLAY 0.468085 (-3475 775);
PAINT GREEN (-3475 775);
DISPLAY INVISIBLE (-3475 775);
FORCEPROP 1 LAST NEEDS_NO_SIZE TRUE
J 0
(-3475 775);
DISPLAY 0.723404 (-3475 775);
PAINT GREEN (-3475 775);
DISPLAY INVISIBLE (-3475 775);
FORCEPROP 1 LAST PATH I95
J 0
(-3475 775);
DISPLAY 0.723404 (-3475 775);
PAINT GREEN (-3475 775);
DISPLAY INVISIBLE (-3475 775);
FORCEPROP 1 LAST PART_NUMBER TP33
J 0
(-3625 925);
DISPLAY 0.723404 (-3625 925);
PAINT GREEN (-3625 925);
DISPLAY INVISIBLE (-3625 925);
FORCEADD PICOPROBE_BXA..1
R 4
(-1550 825);
FORCEPROP 1 LAST LOCATION J121
R 2
J 0
(-1400 625);
DISPLAY 0.723404 (-1400 625);
PAINT GREEN (-1400 625);
FORCEPROP 2 LAST SEC 1
J 0
(-1250 950);
DISPLAY 0.680851 (-1250 950);
PAINT MONO (-1250 950);
DISPLAY INVISIBLE (-1250 950);
FORCEPROP 2 LASTPIN (-1850 825) $PN 1
J 2
(-1860 835);
DISPLAY 0.680851 (-1860 835);
PAINT MONO (-1860 835);
FORCEPROP 2 LASTPIN (-1850 775) $PN 2
J 2
(-1860 785);
DISPLAY 0.680851 (-1860 785);
PAINT MONO (-1860 785);
FORCEPROP 2 LASTPIN (-1250 775) $PN 3
J 0
(-1240 785);
DISPLAY 0.680851 (-1240 785);
PAINT MONO (-1240 785);
FORCEPROP 1 LAST MATERIAL EMPTY
R 2
J 0
(-1396 720);
DISPLAY 0.723404 (-1396 720);
PAINT GREEN (-1396 720);
FORCEPROP 2 LAST VALUE DELTA-L 4.0
R 2
J 0
(-1350 1000);
DISPLAY 0.680851 (-1350 1000);
FORCEPROP 2 LAST PART_TYPE SMLF
R 2
J 0
(-1350 975);
DISPLAY 0.680851 (-1350 975);
FORCEPROP 1 LAST NEEDS_NO_SIZE TRUE
R 2
J 0
(-1550 825);
DISPLAY 0.723404 (-1550 825);
PAINT GREEN (-1550 825);
DISPLAY INVISIBLE (-1550 825);
FORCEPROP 1 LAST CDS_LMAN_SYM_OUTLINE -150,100,150,-100
R 2
J 0
(-1550 825);
DISPLAY 0.468085 (-1550 825);
PAINT GREEN (-1550 825);
DISPLAY INVISIBLE (-1550 825);
FORCEPROP 2 LAST CDS_LIB pure_quanta
J 0
(-1550 825);
DISPLAY INVISIBLE (-1550 825);
FORCEPROP 2 LAST SEC_TYPE 
J 0
(-1250 950);
DISPLAY 0.680851 (-1250 950);
DISPLAY INVISIBLE (-1250 950);
FORCEPROP 1 LAST PATH I96
R 2
J 0
(-1550 825);
DISPLAY 0.723404 (-1550 825);
PAINT GREEN (-1550 825);
DISPLAY INVISIBLE (-1550 825);
FORCEPROP 1 LAST PART_NUMBER TP33
R 2
J 0
(-1400 675);
DISPLAY 0.723404 (-1400 675);
PAINT GREEN (-1400 675);
DISPLAY INVISIBLE (-1400 675);
FORCEADD QUANTA_TITLE_BLOCK_C..1
(0 0);
FORCEPROP 0 LAST CDS_CON_LAST_MODIFIED Thu Sep 14 16:13:12 2023
J 0
(-1885 15);
DISPLAY INVISIBLE (-1885 15);
FORCEPROP 1 LAST CUSTOM_TXT_CDS <CON_LAST_MODIFIED>
J 0
(-1885 15);
DISPLAY 0.978723 (-1885 15);
FORCEPROP 2 LAST CUSTOM_TXT_CDS <XR_PAGE_TITLE>
J 0
(-7890 5250);
DISPLAY 0.638298 (-7890 5250);
PAINT PINK (-7890 5250);
DISPLAY INVISIBLE (-7890 5250);
FORCEPROP 1 LAST CUSTOM_TXT_CDS <NAME_2>
J 0
(-3175 50);
FORCEPROP 1 LAST CUSTOM_TXT_CDS <NAME_1>
J 0
(-3175 175);
FORCEPROP 1 LAST CUSTOM_TXT_CDS <Q_NUMBER>
J 0
(-1403 103);
DISPLAY 1.212766 (-1403 103);
FORCEPROP 1 LAST CUSTOM_TXT_CDS <Q_PROJ>
J 0
(-2382 102);
DISPLAY 1.212766 (-2382 102);
FORCEPROP 1 LAST CUSTOM_TXT_CDS <Q_REV>
J 0
(-184 103);
DISPLAY 1.212766 (-184 103);
FORCEPROP 1 LAST CUSTOM_TXT_CDS <CON_PAGE_NUM> OF <CON_TOTAL_PAGES>
J 0
(-446 18);
DISPLAY 0.978723 (-446 18);
FORCEPROP 1 LAST Q_TITLE DELTA-L
J 0
(-9366 26);
DISPLAY 2.446809 (-9366 26);
PAINT GREEN (-9366 26);
FORCEPROP 2 LAST PAGE_BORDER TRUE
J 0
(-7890 5250);
DISPLAY 0.638298 (-7890 5250);
PAINT PINK (-7890 5250);
DISPLAY INVISIBLE (-7890 5250);
FORCEPROP 1 LAST CDS_LMAN_SYM_OUTLINE -9475,6775,100,-125
J 0
(0 0);
DISPLAY 0.468085 (0 0);
PAINT GREEN (0 0);
DISPLAY INVISIBLE (0 0);
FORCEPROP 2 LAST CDS_LIB pure_quanta
J 0
(0 0);
DISPLAY INVISIBLE (0 0);
FORCEPROP 2 LAST CDS_XR_PAGE_TITLE CR-229 : @T6G_MB_LIB.T6G(SCH_1):PAGE229
J 0
(-7890 5250);
DISPLAY 0.638298 (-7890 5250);
PAINT PINK (-7890 5250);
DISPLAY INVISIBLE (-7890 5250);
FORCEPROP 1 LAST Q_DEPT BU9
J 1
(-3763 49);
DISPLAY 1.957447 (-3763 49);
PAINT GREEN (-3763 49);
DISPLAY INVISIBLE (-3763 49);
FORCEPROP 1 LAST COMMENT_BODY TRUE
J 0
(12 -13);
DISPLAY 0.978723 (12 -13);
PAINT GREEN (12 -13);
DISPLAY INVISIBLE (12 -13);
WIRE 16 -1 (-6175 3625)(-7375 3625);
FORCEPROP 0 LAST CDS_PHYS_NET_NAME DELTA_L_85_5INCH_IN2_DN
J 0
(-7335 3665);
PAINT MONO (-7335 3665);
DISPLAY INVISIBLE (-7335 3665);
FORCEPROP 2 LAST SIG_NAME DELTA_L_85_5INCH_IN2_DN
J 0
(-7060 3635);
DISPLAY 0.638298 (-7060 3635);
PAINT WHITE (-7060 3635);
FORCEPROP 2 LASTPROP $XRERR UNIQUE?
J 0
(-7300 3635);
DISPLAY 0.638298 (-7300 3635);
PAINT MONO (-7300 3635);
DISPLAY INVISIBLE (-7300 3635);
WIRE 16 -1 (-6050 1500)(-7375 1500);
FORCEPROP 0 LAST CDS_PHYS_NET_NAME DELTA_L_85_5INCH_IN5_DN
J 0
(-7335 1540);
PAINT MONO (-7335 1540);
DISPLAY INVISIBLE (-7335 1540);
FORCEPROP 2 LAST SIG_NAME DELTA_L_85_5INCH_IN5_DN
J 0
(-7060 1510);
DISPLAY 0.638298 (-7060 1510);
PAINT WHITE (-7060 1510);
FORCEPROP 2 LASTPROP $XRERR UNIQUE?
J 0
(-7300 1510);
DISPLAY 0.638298 (-7300 1510);
PAINT MONO (-7300 1510);
DISPLAY INVISIBLE (-7300 1510);
WIRE 16 -1 (-6025 750)(-7425 750);
FORCEPROP 0 LAST CDS_PHYS_NET_NAME DELTA_L_85_5INCH_IN6_DP
J 0
(-7385 790);
PAINT MONO (-7385 790);
DISPLAY INVISIBLE (-7385 790);
FORCEPROP 2 LAST SIG_NAME DELTA_L_85_5INCH_IN6_DP
J 0
(-7110 760);
DISPLAY 0.638298 (-7110 760);
PAINT WHITE (-7110 760);
FORCEPROP 2 LASTPROP $XRERR UNIQUE?
J 0
(-7350 760);
DISPLAY 0.638298 (-7350 760);
PAINT MONO (-7350 760);
DISPLAY INVISIBLE (-7350 760);
WIRE 16 -1 (-6025 800)(-7425 800);
FORCEPROP 0 LAST CDS_PHYS_NET_NAME DELTA_L_85_5INCH_IN6_DN
J 0
(-7385 840);
PAINT MONO (-7385 840);
DISPLAY INVISIBLE (-7385 840);
FORCEPROP 2 LAST SIG_NAME DELTA_L_85_5INCH_IN6_DN
J 0
(-7110 810);
DISPLAY 0.638298 (-7110 810);
PAINT WHITE (-7110 810);
FORCEPROP 2 LASTPROP $XRERR UNIQUE?
J 0
(-7350 810);
DISPLAY 0.638298 (-7350 810);
PAINT MONO (-7350 810);
DISPLAY INVISIBLE (-7350 810);
WIRE 16 -1 (-6175 5100)(-7350 5100);
FORCEPROP 0 LAST CDS_PHYS_NET_NAME DELTA_L_85_5INCH_BOT_DN
J 0
(-7310 5140);
PAINT MONO (-7310 5140);
DISPLAY INVISIBLE (-7310 5140);
FORCEPROP 2 LAST SIG_NAME DELTA_L_85_5INCH_BOT_DN
J 0
(-7035 5110);
DISPLAY 0.638298 (-7035 5110);
PAINT WHITE (-7035 5110);
FORCEPROP 2 LASTPROP $XRERR UNIQUE?
J 0
(-7275 5110);
DISPLAY 0.638298 (-7275 5110);
PAINT MONO (-7275 5110);
DISPLAY INVISIBLE (-7275 5110);
WIRE 16 -1 (-6175 5050)(-7350 5050);
FORCEPROP 0 LAST CDS_PHYS_NET_NAME DELTA_L_85_5INCH_BOT_DP
J 0
(-7310 5090);
PAINT MONO (-7310 5090);
DISPLAY INVISIBLE (-7310 5090);
FORCEPROP 2 LAST SIG_NAME DELTA_L_85_5INCH_BOT_DP
J 0
(-7035 5060);
DISPLAY 0.638298 (-7035 5060);
PAINT WHITE (-7035 5060);
FORCEPROP 2 LASTPROP $XRERR UNIQUE?
J 0
(-7275 5060);
DISPLAY 0.638298 (-7275 5060);
PAINT MONO (-7275 5060);
DISPLAY INVISIBLE (-7275 5060);
WIRE 16 -1 (-6175 4350)(-7375 4350);
FORCEPROP 0 LAST CDS_PHYS_NET_NAME DELTA_L_85_5INCH_IN1_DN
J 0
(-7335 4390);
PAINT MONO (-7335 4390);
DISPLAY INVISIBLE (-7335 4390);
FORCEPROP 2 LAST SIG_NAME DELTA_L_85_5INCH_IN1_DN
J 0
(-7060 4360);
DISPLAY 0.638298 (-7060 4360);
PAINT WHITE (-7060 4360);
FORCEPROP 2 LASTPROP $XRERR UNIQUE?
J 0
(-7300 4360);
DISPLAY 0.638298 (-7300 4360);
PAINT MONO (-7300 4360);
DISPLAY INVISIBLE (-7300 4360);
WIRE 16 -1 (-6175 4300)(-7375 4300);
FORCEPROP 0 LAST CDS_PHYS_NET_NAME DELTA_L_85_5INCH_IN1_DP
J 0
(-7335 4340);
PAINT MONO (-7335 4340);
DISPLAY INVISIBLE (-7335 4340);
FORCEPROP 2 LAST SIG_NAME DELTA_L_85_5INCH_IN1_DP
J 0
(-7060 4310);
DISPLAY 0.638298 (-7060 4310);
PAINT WHITE (-7060 4310);
FORCEPROP 2 LASTPROP $XRERR UNIQUE?
J 0
(-7300 4310);
DISPLAY 0.638298 (-7300 4310);
PAINT MONO (-7300 4310);
DISPLAY INVISIBLE (-7300 4310);
WIRE 16 -1 (-6175 3575)(-7375 3575);
FORCEPROP 0 LAST CDS_PHYS_NET_NAME DELTA_L_85_5INCH_IN2_DP
J 0
(-7335 3615);
PAINT MONO (-7335 3615);
DISPLAY INVISIBLE (-7335 3615);
FORCEPROP 2 LAST SIG_NAME DELTA_L_85_5INCH_IN2_DP
J 0
(-7060 3585);
DISPLAY 0.638298 (-7060 3585);
PAINT WHITE (-7060 3585);
FORCEPROP 2 LASTPROP $XRERR UNIQUE?
J 0
(-7300 3585);
DISPLAY 0.638298 (-7300 3585);
PAINT MONO (-7300 3585);
DISPLAY INVISIBLE (-7300 3585);
WIRE 16 -1 (-6125 2950)(-7400 2950);
FORCEPROP 0 LAST CDS_PHYS_NET_NAME DELTA_L_85_5INCH_IN3_DN
J 0
(-7360 2990);
PAINT MONO (-7360 2990);
DISPLAY INVISIBLE (-7360 2990);
FORCEPROP 2 LAST SIG_NAME DELTA_L_85_5INCH_IN3_DN
J 0
(-7085 2960);
DISPLAY 0.638298 (-7085 2960);
PAINT WHITE (-7085 2960);
FORCEPROP 2 LASTPROP $XRERR UNIQUE?
J 0
(-7325 2960);
DISPLAY 0.638298 (-7325 2960);
PAINT MONO (-7325 2960);
DISPLAY INVISIBLE (-7325 2960);
WIRE 16 -1 (-6050 2200)(-7350 2200);
FORCEPROP 0 LAST CDS_PHYS_NET_NAME DELTA_L_85_5INCH_IN4_DN
J 0
(-7310 2240);
PAINT MONO (-7310 2240);
DISPLAY INVISIBLE (-7310 2240);
FORCEPROP 2 LAST SIG_NAME DELTA_L_85_5INCH_IN4_DN
J 0
(-7035 2210);
DISPLAY 0.638298 (-7035 2210);
PAINT WHITE (-7035 2210);
FORCEPROP 2 LASTPROP $XRERR UNIQUE?
J 0
(-7275 2210);
DISPLAY 0.638298 (-7275 2210);
PAINT MONO (-7275 2210);
DISPLAY INVISIBLE (-7275 2210);
WIRE 16 -1 (-6050 2150)(-7350 2150);
FORCEPROP 0 LAST CDS_PHYS_NET_NAME DELTA_L_85_5INCH_IN4_DP
J 0
(-7310 2190);
PAINT MONO (-7310 2190);
DISPLAY INVISIBLE (-7310 2190);
FORCEPROP 2 LAST SIG_NAME DELTA_L_85_5INCH_IN4_DP
J 0
(-7035 2160);
DISPLAY 0.638298 (-7035 2160);
PAINT WHITE (-7035 2160);
FORCEPROP 2 LASTPROP $XRERR UNIQUE?
J 0
(-7275 2160);
DISPLAY 0.638298 (-7275 2160);
PAINT MONO (-7275 2160);
DISPLAY INVISIBLE (-7275 2160);
WIRE 16 -1 (-6050 1450)(-7375 1450);
FORCEPROP 0 LAST CDS_PHYS_NET_NAME DELTA_L_85_5INCH_IN5_DP
J 0
(-7335 1490);
PAINT MONO (-7335 1490);
DISPLAY INVISIBLE (-7335 1490);
FORCEPROP 2 LAST SIG_NAME DELTA_L_85_5INCH_IN5_DP
J 0
(-7060 1460);
DISPLAY 0.638298 (-7060 1460);
PAINT WHITE (-7060 1460);
FORCEPROP 2 LASTPROP $XRERR UNIQUE?
J 0
(-7300 1460);
DISPLAY 0.638298 (-7300 1460);
PAINT MONO (-7300 1460);
DISPLAY INVISIBLE (-7300 1460);
WIRE 16 -1 (-6175 5775)(-7350 5775);
FORCEPROP 0 LAST CDS_PHYS_NET_NAME DELTA_L_85_5INCH_TOP_DP
J 0
(-7310 5815);
PAINT MONO (-7310 5815);
DISPLAY INVISIBLE (-7310 5815);
FORCEPROP 2 LAST SIG_NAME DELTA_L_85_5INCH_TOP_DP
J 0
(-7035 5785);
DISPLAY 0.638298 (-7035 5785);
PAINT WHITE (-7035 5785);
FORCEPROP 2 LASTPROP $XRERR UNIQUE?
J 0
(-7275 5785);
DISPLAY 0.638298 (-7275 5785);
PAINT MONO (-7275 5785);
DISPLAY INVISIBLE (-7275 5785);
WIRE 16 -1 (-6175 5825)(-7350 5825);
FORCEPROP 0 LAST CDS_PHYS_NET_NAME DELTA_L_85_5INCH_TOP_DN
J 0
(-7310 5865);
PAINT MONO (-7310 5865);
DISPLAY INVISIBLE (-7310 5865);
FORCEPROP 2 LAST SIG_NAME DELTA_L_85_5INCH_TOP_DN
J 0
(-7035 5835);
DISPLAY 0.638298 (-7035 5835);
PAINT WHITE (-7035 5835);
FORCEPROP 2 LASTPROP $XRERR UNIQUE?
J 0
(-7275 5835);
DISPLAY 0.638298 (-7275 5835);
PAINT MONO (-7275 5835);
DISPLAY INVISIBLE (-7275 5835);
WIRE 16 -1 (-1925 5850)(-3225 5850);
FORCEPROP 0 LAST CDS_PHYS_NET_NAME DELTA_L_85_10INCH_TOP_DN
J 0
(-3185 5890);
PAINT MONO (-3185 5890);
DISPLAY INVISIBLE (-3185 5890);
FORCEPROP 2 LAST SIG_NAME DELTA_L_85_10INCH_TOP_DN
J 0
(-2910 5860);
DISPLAY 0.638298 (-2910 5860);
PAINT WHITE (-2910 5860);
FORCEPROP 2 LASTPROP $XRERR UNIQUE?
J 0
(-3150 5860);
DISPLAY 0.638298 (-3150 5860);
PAINT MONO (-3150 5860);
DISPLAY INVISIBLE (-3150 5860);
WIRE 16 -1 (-1925 5800)(-3225 5800);
FORCEPROP 0 LAST CDS_PHYS_NET_NAME DELTA_L_85_10INCH_TOP_DP
J 0
(-3185 5840);
PAINT MONO (-3185 5840);
DISPLAY INVISIBLE (-3185 5840);
FORCEPROP 2 LAST SIG_NAME DELTA_L_85_10INCH_TOP_DP
J 0
(-2910 5810);
DISPLAY 0.638298 (-2910 5810);
PAINT WHITE (-2910 5810);
FORCEPROP 2 LASTPROP $XRERR UNIQUE?
J 0
(-3150 5810);
DISPLAY 0.638298 (-3150 5810);
PAINT MONO (-3150 5810);
DISPLAY INVISIBLE (-3150 5810);
WIRE 16 -1 (-1925 5100)(-3275 5100);
FORCEPROP 0 LAST CDS_PHYS_NET_NAME DELTA_L_85_10INCH_BOT_DN
J 0
(-3235 5140);
PAINT MONO (-3235 5140);
DISPLAY INVISIBLE (-3235 5140);
FORCEPROP 2 LAST SIG_NAME DELTA_L_85_10INCH_BOT_DN
J 0
(-2960 5110);
DISPLAY 0.638298 (-2960 5110);
PAINT WHITE (-2960 5110);
FORCEPROP 2 LASTPROP $XRERR UNIQUE?
J 0
(-3200 5110);
DISPLAY 0.638298 (-3200 5110);
PAINT MONO (-3200 5110);
DISPLAY INVISIBLE (-3200 5110);
WIRE 16 -1 (-1925 5050)(-3275 5050);
FORCEPROP 0 LAST CDS_PHYS_NET_NAME DELTA_L_85_10INCH_BOT_DP
J 0
(-3235 5090);
PAINT MONO (-3235 5090);
DISPLAY INVISIBLE (-3235 5090);
FORCEPROP 2 LAST SIG_NAME DELTA_L_85_10INCH_BOT_DP
J 0
(-2960 5060);
DISPLAY 0.638298 (-2960 5060);
PAINT WHITE (-2960 5060);
FORCEPROP 2 LASTPROP $XRERR UNIQUE?
J 0
(-3200 5060);
DISPLAY 0.638298 (-3200 5060);
PAINT MONO (-3200 5060);
DISPLAY INVISIBLE (-3200 5060);
WIRE 16 -1 (-1975 4375)(-3225 4375);
FORCEPROP 0 LAST CDS_PHYS_NET_NAME DELTA_L_85_10INCH_IN1_DN
J 0
(-3185 4415);
PAINT MONO (-3185 4415);
DISPLAY INVISIBLE (-3185 4415);
FORCEPROP 2 LAST SIG_NAME DELTA_L_85_10INCH_IN1_DN
J 0
(-2910 4385);
DISPLAY 0.638298 (-2910 4385);
PAINT WHITE (-2910 4385);
FORCEPROP 2 LASTPROP $XRERR UNIQUE?
J 0
(-3150 4385);
DISPLAY 0.638298 (-3150 4385);
PAINT MONO (-3150 4385);
DISPLAY INVISIBLE (-3150 4385);
WIRE 16 -1 (-1975 4325)(-3225 4325);
FORCEPROP 0 LAST CDS_PHYS_NET_NAME DELTA_L_85_10INCH_IN1_DP
J 0
(-3185 4365);
PAINT MONO (-3185 4365);
DISPLAY INVISIBLE (-3185 4365);
FORCEPROP 2 LAST SIG_NAME DELTA_L_85_10INCH_IN1_DP
J 0
(-2910 4335);
DISPLAY 0.638298 (-2910 4335);
PAINT WHITE (-2910 4335);
FORCEPROP 2 LASTPROP $XRERR UNIQUE?
J 0
(-3150 4335);
DISPLAY 0.638298 (-3150 4335);
PAINT MONO (-3150 4335);
DISPLAY INVISIBLE (-3150 4335);
WIRE 16 -1 (-1900 3625)(-3250 3625);
FORCEPROP 0 LAST CDS_PHYS_NET_NAME DELTA_L_85_10INCH_IN2_DN
J 0
(-3210 3665);
PAINT MONO (-3210 3665);
DISPLAY INVISIBLE (-3210 3665);
FORCEPROP 2 LAST SIG_NAME DELTA_L_85_10INCH_IN2_DN
J 0
(-2935 3635);
DISPLAY 0.638298 (-2935 3635);
PAINT WHITE (-2935 3635);
FORCEPROP 2 LASTPROP $XRERR UNIQUE?
J 0
(-3175 3635);
DISPLAY 0.638298 (-3175 3635);
PAINT MONO (-3175 3635);
DISPLAY INVISIBLE (-3175 3635);
WIRE 16 -1 (-1900 3575)(-3250 3575);
FORCEPROP 0 LAST CDS_PHYS_NET_NAME DELTA_L_85_10INCH_IN2_DP
J 0
(-3210 3615);
PAINT MONO (-3210 3615);
DISPLAY INVISIBLE (-3210 3615);
FORCEPROP 2 LAST SIG_NAME DELTA_L_85_10INCH_IN2_DP
J 0
(-2935 3585);
DISPLAY 0.638298 (-2935 3585);
PAINT WHITE (-2935 3585);
FORCEPROP 2 LASTPROP $XRERR UNIQUE?
J 0
(-3175 3585);
DISPLAY 0.638298 (-3175 3585);
PAINT MONO (-3175 3585);
DISPLAY INVISIBLE (-3175 3585);
WIRE 16 -1 (-1925 2900)(-3275 2900);
FORCEPROP 0 LAST CDS_PHYS_NET_NAME DELTA_L_85_10INCH_IN3_DP
J 0
(-3235 2940);
PAINT MONO (-3235 2940);
DISPLAY INVISIBLE (-3235 2940);
FORCEPROP 2 LAST SIG_NAME DELTA_L_85_10INCH_IN3_DP
J 0
(-2960 2910);
DISPLAY 0.638298 (-2960 2910);
PAINT WHITE (-2960 2910);
FORCEPROP 2 LASTPROP $XRERR UNIQUE?
J 0
(-3200 2910);
DISPLAY 0.638298 (-3200 2910);
PAINT MONO (-3200 2910);
DISPLAY INVISIBLE (-3200 2910);
WIRE 16 -1 (-1925 2950)(-3275 2950);
FORCEPROP 0 LAST CDS_PHYS_NET_NAME DELTA_L_85_10INCH_IN3_DN
J 0
(-3235 2990);
PAINT MONO (-3235 2990);
DISPLAY INVISIBLE (-3235 2990);
FORCEPROP 2 LAST SIG_NAME DELTA_L_85_10INCH_IN3_DN
J 0
(-2960 2960);
DISPLAY 0.638298 (-2960 2960);
PAINT WHITE (-2960 2960);
FORCEPROP 2 LASTPROP $XRERR UNIQUE?
J 0
(-3200 2960);
DISPLAY 0.638298 (-3200 2960);
PAINT MONO (-3200 2960);
DISPLAY INVISIBLE (-3200 2960);
WIRE 16 -1 (-3875 2950)(-4100 2950);
WIRE 16 -1 (-4100 2825)(-4100 2950);
WIRE 16 -1 (-1075 2800)(-1075 2900);
WIRE 16 -1 (-1075 2900)(-1325 2900);
WIRE 16 -1 (-3850 3625)(-4100 3625);
WIRE 16 -1 (-4100 3475)(-4100 3625);
WIRE 16 -1 (-7950 2200)(-8125 2200);
WIRE 16 -1 (-8125 2025)(-8125 2200);
WIRE 16 -1 (-5175 600)(-5175 750);
WIRE 16 -1 (-5175 750)(-5425 750);
WIRE 16 -1 (-5225 1375)(-5225 1450);
WIRE 16 -1 (-5225 1450)(-5450 1450);
WIRE 16 -1 (-8000 2950)(-8150 2950);
WIRE 16 -1 (-8150 2775)(-8150 2950);
WIRE 16 -1 (-5250 2150)(-5450 2150);
WIRE 16 -1 (-5250 2025)(-5250 2150);
WIRE 16 -1 (-5375 2900)(-5525 2900);
WIRE 16 -1 (-5375 2725)(-5375 2900);
WIRE 16 -1 (-5375 3450)(-5375 3575);
WIRE 16 -1 (-5375 3575)(-5575 3575);
WIRE 16 -1 (-5350 4200)(-5350 4300);
WIRE 16 -1 (-5350 4300)(-5575 4300);
WIRE 16 -1 (-7975 3625)(-8125 3625);
WIRE 16 -1 (-8125 3450)(-8125 3625);
WIRE 16 -1 (-5375 5050)(-5575 5050);
WIRE 16 -1 (-5375 4925)(-5375 5050);
WIRE 16 -1 (-5375 5700)(-5375 5775);
WIRE 16 -1 (-5375 5775)(-5575 5775);
WIRE 16 -1 (-8125 4350)(-7975 4350);
WIRE 16 -1 (-8125 4175)(-8125 4350);
WIRE 16 -1 (-3825 4375)(-4050 4375);
WIRE 16 -1 (-4050 4200)(-4050 4375);
WIRE 16 -1 (-8125 5100)(-7950 5100);
WIRE 16 -1 (-8125 4925)(-8125 5100);
WIRE 16 -1 (-1075 3475)(-1075 3575);
WIRE 16 -1 (-1075 3575)(-1300 3575);
WIRE 16 -1 (-1050 4175)(-1050 4325);
WIRE 16 -1 (-1050 4325)(-1375 4325);
WIRE 16 -1 (-4075 4925)(-4075 5100);
WIRE 16 -1 (-4075 5100)(-3875 5100);
WIRE 16 -1 (-3825 5850)(-4075 5850);
WIRE 16 -1 (-4075 5725)(-4075 5850);
WIRE 16 -1 (-7950 5825)(-8125 5825);
WIRE 16 -1 (-8125 5750)(-8125 5825);
WIRE 16 -1 (-1200 4925)(-1200 5050);
WIRE 16 -1 (-1200 5050)(-1325 5050);
WIRE 16 -1 (-975 5725)(-975 5800);
WIRE 16 -1 (-975 5800)(-1325 5800);
WIRE 16 -1 (-8100 1500)(-7975 1500);
WIRE 16 -1 (-8100 1375)(-8100 1500);
WIRE 16 -1 (-8075 800)(-8025 800);
WIRE 16 -1 (-8075 625)(-8075 800);
WIRE 16 -1 (-3825 2200)(-4100 2200);
WIRE 16 -1 (-4100 2050)(-4100 2200);
WIRE 16 -1 (-1025 2150)(-1300 2150);
WIRE 16 -1 (-1025 2075)(-1025 2150);
WIRE 16 -1 (-1025 1500)(-1275 1500);
WIRE 16 -1 (-1025 1425)(-1025 1500);
WIRE 16 -1 (-3775 1550)(-4050 1550);
WIRE 16 -1 (-4050 1250)(-4050 1550);
WIRE 16 -1 (-3775 825)(-4025 825);
WIRE 16 -1 (-4025 700)(-4025 825);
WIRE 16 -1 (-1850 775)(-3175 775);
FORCEPROP 0 LAST CDS_PHYS_NET_NAME DELTA_L_85_10INCH_IN6_DP
J 0
(-3135 815);
PAINT MONO (-3135 815);
DISPLAY INVISIBLE (-3135 815);
FORCEPROP 2 LAST SIG_NAME DELTA_L_85_10INCH_IN6_DP
J 0
(-2860 785);
DISPLAY 0.638298 (-2860 785);
PAINT WHITE (-2860 785);
FORCEPROP 2 LASTPROP $XRERR UNIQUE?
J 0
(-3100 785);
DISPLAY 0.638298 (-3100 785);
PAINT MONO (-3100 785);
DISPLAY INVISIBLE (-3100 785);
WIRE 16 -1 (-1850 825)(-3175 825);
FORCEPROP 0 LAST CDS_PHYS_NET_NAME DELTA_L_85_10INCH_IN6_DN
J 0
(-3135 865);
PAINT MONO (-3135 865);
DISPLAY INVISIBLE (-3135 865);
FORCEPROP 2 LAST SIG_NAME DELTA_L_85_10INCH_IN6_DN
J 0
(-2860 835);
DISPLAY 0.638298 (-2860 835);
PAINT WHITE (-2860 835);
FORCEPROP 2 LASTPROP $XRERR UNIQUE?
J 0
(-3100 835);
DISPLAY 0.638298 (-3100 835);
PAINT MONO (-3100 835);
DISPLAY INVISIBLE (-3100 835);
WIRE 16 -1 (-6125 2900)(-7400 2900);
FORCEPROP 0 LAST CDS_PHYS_NET_NAME DELTA_L_85_5INCH_IN3_DP
J 0
(-7360 2940);
PAINT MONO (-7360 2940);
DISPLAY INVISIBLE (-7360 2940);
FORCEPROP 2 LAST SIG_NAME DELTA_L_85_5INCH_IN3_DP
J 0
(-7085 2910);
DISPLAY 0.638298 (-7085 2910);
PAINT WHITE (-7085 2910);
FORCEPROP 2 LASTPROP $XRERR UNIQUE?
J 0
(-7325 2910);
DISPLAY 0.638298 (-7325 2910);
PAINT MONO (-7325 2910);
DISPLAY INVISIBLE (-7325 2910);
WIRE 16 -1 (-1900 2200)(-3225 2200);
FORCEPROP 0 LAST CDS_PHYS_NET_NAME DELTA_L_85_10INCH_IN4_DN
J 0
(-3185 2240);
PAINT MONO (-3185 2240);
DISPLAY INVISIBLE (-3185 2240);
FORCEPROP 2 LAST SIG_NAME DELTA_L_85_10INCH_IN4_DN
J 0
(-2910 2210);
DISPLAY 0.638298 (-2910 2210);
PAINT WHITE (-2910 2210);
FORCEPROP 2 LASTPROP $XRERR UNIQUE?
J 0
(-3150 2210);
DISPLAY 0.638298 (-3150 2210);
PAINT MONO (-3150 2210);
DISPLAY INVISIBLE (-3150 2210);
WIRE 16 -1 (-1125 775)(-1250 775);
WIRE 16 -1 (-1125 650)(-1125 775);
WIRE 16 -1 (-1875 1500)(-3175 1500);
FORCEPROP 0 LAST CDS_PHYS_NET_NAME DELTA_L_85_10INCH_IN5_DP
J 0
(-3135 1540);
PAINT MONO (-3135 1540);
DISPLAY INVISIBLE (-3135 1540);
FORCEPROP 2 LAST SIG_NAME DELTA_L_85_10INCH_IN5_DP
J 0
(-2860 1510);
DISPLAY 0.638298 (-2860 1510);
PAINT WHITE (-2860 1510);
FORCEPROP 2 LASTPROP $XRERR UNIQUE?
J 0
(-3100 1510);
DISPLAY 0.638298 (-3100 1510);
PAINT MONO (-3100 1510);
DISPLAY INVISIBLE (-3100 1510);
WIRE 16 -1 (-1875 1550)(-3175 1550);
FORCEPROP 0 LAST CDS_PHYS_NET_NAME DELTA_L_85_10INCH_IN5_DN
J 0
(-3135 1590);
PAINT MONO (-3135 1590);
DISPLAY INVISIBLE (-3135 1590);
FORCEPROP 2 LAST SIG_NAME DELTA_L_85_10INCH_IN5_DN
J 0
(-2860 1560);
DISPLAY 0.638298 (-2860 1560);
PAINT WHITE (-2860 1560);
FORCEPROP 2 LASTPROP $XRERR UNIQUE?
J 0
(-3100 1560);
DISPLAY 0.638298 (-3100 1560);
PAINT MONO (-3100 1560);
DISPLAY INVISIBLE (-3100 1560);
WIRE 16 -1 (-1900 2150)(-3225 2150);
FORCEPROP 0 LAST CDS_PHYS_NET_NAME DELTA_L_85_10INCH_IN4_DP
J 0
(-3185 2190);
PAINT MONO (-3185 2190);
DISPLAY INVISIBLE (-3185 2190);
FORCEPROP 2 LAST SIG_NAME DELTA_L_85_10INCH_IN4_DP
J 0
(-2910 2160);
DISPLAY 0.638298 (-2910 2160);
PAINT WHITE (-2910 2160);
FORCEPROP 2 LASTPROP $XRERR UNIQUE?
J 0
(-3150 2160);
DISPLAY 0.638298 (-3150 2160);
PAINT MONO (-3150 2160);
DISPLAY INVISIBLE (-3150 2160);
FORCENOTE
5 INCH
(-7375 6275) 0;
DISPLAY LEFT (-7375 6275);
DISPLAY 3.936170 (-7375 6275);
FORCENOTE
10 INCH
(-3200 6275) 0;
DISPLAY LEFT (-3200 6275);
DISPLAY 3.936170 (-3200 6275);
QUIT
